FILE_TYPE = MACRO_DRAWING;
SET COLOR_WIRE YELLOW;
SET COLOR_PROP MONO;
SET COLOR_DOT WHITE;
SET COLOR_ARC YELLOW;
SET COLOR_BODY GREEN;
SET COLOR_NOTE MONO;
SET PROP_DISPLAY VALUE;
SET PAGE_NUMBER P217;
FORCEADD PVDDQ_ABC..1
(2900 2000);
FORCEPROP 3 LASTPIN (2900 1950) SIG_NAME PVDDQ_ABC\g
J 0
(2910 1960);
DISPLAY 0.659574 (2910 1960);
PAINT MONO (2910 1960);
DISPLAY INVISIBLE (2910 1960);
FORCEPROP 2 LAST CDS_LIB mstr_symbols
J 0
(2900 2000);
PAINT ORANGE (2900 2000);
DISPLAY INVISIBLE (2900 2000);
FORCEPROP 1 LAST VOLTAGE 1.2V
J 0
(2855 1957);
DISPLAY 0.340426 (2855 1957);
PAINT SKYBLUE (2855 1957);
DISPLAY INVISIBLE (2855 1957);
FORCEPROP 1 LAST PATH I109
J 0
(2950 2025);
DISPLAY 0.872340 (2950 2025);
PAINT AQUA (2950 2025);
DISPLAY INVISIBLE (2950 2025);
FORCEPROP 1 LAST BODY_TYPE PLUMBING
J 0
(2855 1957);
DISPLAY 0.340426 (2855 1957);
PAINT GREEN (2855 1957);
DISPLAY INVISIBLE (2855 1957);
FORCEPROP 1 LAST HDL_POWER PVDDQ_ABC
J 1
(2900 2050);
DISPLAY 0.872340 (2900 2050);
PAINT GREEN (2900 2050);
DISPLAY INVISIBLE (2900 2050);
FORCEADD GND..1
(4625 1350);
FORCEPROP 3 LASTPIN (4625 1400) SIG_NAME GND\g
J 0
(4635 1410);
DISPLAY 0.659574 (4635 1410);
PAINT MONO (4635 1410);
DISPLAY INVISIBLE (4635 1410);
FORCEPROP 2 LAST ROOM VDDQ_ABC_PWR_VR
J 0
(4075 1425);
PAINT ORANGE (4075 1425);
DISPLAY INVISIBLE (4075 1425);
FORCEPROP 2 LAST BOM_COST MEM_VRD_PVDDQ_CD
J 0
(4300 1425);
PAINT MONO (4300 1425);
DISPLAY INVISIBLE (4300 1425);
FORCEPROP 1 LAST SIZE 1B
J 0
(4700 1300);
DISPLAY 0.893617 (4700 1300);
PAINT GREEN (4700 1300);
DISPLAY INVISIBLE (4700 1300);
FORCEPROP 2 LAST CDS_LIB mstr_symbols
J 0
(4625 1350);
PAINT ORANGE (4625 1350);
DISPLAY INVISIBLE (4625 1350);
FORCEPROP 1 LAST PATH I114
J 0
(4700 1350);
DISPLAY 1.170213 (4700 1350);
PAINT AQUA (4700 1350);
DISPLAY INVISIBLE (4700 1350);
FORCEPROP 1 LAST VOLTAGE 0
J 0
(4625 1350);
PAINT SKYBLUE (4625 1350);
DISPLAY INVISIBLE (4625 1350);
FORCEPROP 1 LAST BODY_TYPE PLUMBING
J 0
(4580 1307);
DISPLAY 0.340426 (4580 1307);
PAINT GREEN (4580 1307);
DISPLAY INVISIBLE (4580 1307);
FORCEPROP 1 LAST HDL_POWER GND
J 0
(4625 1500);
DISPLAY 0.893617 (4625 1500);
PAINT GREEN (4625 1500);
DISPLAY INVISIBLE (4625 1500);
FORCEADD VCC_CORE..1
(200 1150);
FORCEPROP 3 LASTPIN (200 1100) SIG_NAME VR_FET_SW_P12V_STBY_PVDDQ_ABC\g
J 0
(210 1110);
DISPLAY 0.659574 (210 1110);
PAINT MONO (210 1110);
DISPLAY INVISIBLE (210 1110);
FORCEPROP 1 LAST HDL_POWER VR_FET_SW_P12V_STBY_PVDDQ_ABC
J 1
(200 1200);
DISPLAY 0.617021 (200 1200);
PAINT GREEN (200 1200);
FORCEPROP 2 LAST CDS_LIB mstr_symbols
J 0
(200 1150);
PAINT ORANGE (200 1150);
DISPLAY INVISIBLE (200 1150);
FORCEPROP 1 LAST PATH I120
J 0
(250 1175);
DISPLAY 1.170213 (250 1175);
PAINT AQUA (250 1175);
DISPLAY INVISIBLE (250 1175);
FORCEADD GND..1
(200 475);
FORCEPROP 3 LASTPIN (200 525) SIG_NAME GND\g
J 0
(210 535);
DISPLAY 0.659574 (210 535);
PAINT MONO (210 535);
DISPLAY INVISIBLE (210 535);
FORCEPROP 2 LAST ROOM VDDQ_ABC_PWR_VR
J 0
(-350 550);
PAINT ORANGE (-350 550);
DISPLAY INVISIBLE (-350 550);
FORCEPROP 2 LAST BOM_COST MEM_VRD_PVDDQ_CD
J 0
(-125 550);
PAINT MONO (-125 550);
DISPLAY INVISIBLE (-125 550);
FORCEPROP 1 LAST SIZE 1B
J 0
(275 425);
DISPLAY 0.893617 (275 425);
PAINT GREEN (275 425);
DISPLAY INVISIBLE (275 425);
FORCEPROP 2 LAST CDS_LIB mstr_symbols
J 0
(200 475);
PAINT ORANGE (200 475);
DISPLAY INVISIBLE (200 475);
FORCEPROP 1 LAST PATH I123
J 0
(275 475);
DISPLAY 1.170213 (275 475);
PAINT AQUA (275 475);
DISPLAY INVISIBLE (275 475);
FORCEPROP 1 LAST VOLTAGE 0
J 0
(200 475);
PAINT SKYBLUE (200 475);
DISPLAY INVISIBLE (200 475);
FORCEPROP 1 LAST BODY_TYPE PLUMBING
J 0
(155 432);
DISPLAY 0.340426 (155 432);
PAINT GREEN (155 432);
DISPLAY INVISIBLE (155 432);
FORCEPROP 1 LAST HDL_POWER GND
J 0
(200 625);
DISPLAY 0.893617 (200 625);
PAINT GREEN (200 625);
DISPLAY INVISIBLE (200 625);
FORCEADD CAPP..1
(200 700);
FORCEPROP 1 LAST MATERIAL OSCON
J 0
(250 600);
DISPLAY 0.617021 (250 600);
PAINT SKYBLUE (250 600);
FORCEPROP 1 LAST PACK_TYPE 2626
J 0
(250 550);
DISPLAY 0.617021 (250 550);
PAINT SKYBLUE (250 550);
FORCEPROP 1 LASTPIN (200 800) $PN 1
J 0
(210 785);
DISPLAY 0.617021 (210 785);
PAINT ORANGE (210 785);
FORCEPROP 1 LASTPIN (200 600) $PN 2
J 0
(210 585);
DISPLAY 0.617021 (210 585);
PAINT ORANGE (210 585);
FORCEPROP 1 LAST VOLTAGE 16V
J 0
(250 650);
DISPLAY 0.617021 (250 650);
PAINT SKYBLUE (250 650);
FORCEPROP 1 LAST LOCATION C7G2
J 0
(250 800);
DISPLAY 0.617021 (250 800);
PAINT AQUA (250 800);
FORCEPROP 1 LAST TOLERANCE 20%
J 0
(250 700);
DISPLAY 0.617021 (250 700);
PAINT SKYBLUE (250 700);
FORCEPROP 1 LAST VALUE 270UF
J 0
(250 750);
DISPLAY 0.617021 (250 750);
PAINT SKYBLUE (250 750);
FORCEPROP 1 LAST PART_NUMBER A31228-047
J 0
(250 500);
DISPLAY 0.617021 (250 500);
PAINT BLUE (250 500);
FORCEPROP 2 LAST CDS_LIB mstr_discrete
J 0
(200 700);
PAINT ORANGE (200 700);
DISPLAY INVISIBLE (200 700);
FORCEPROP 2 LAST CDS_LOCATION C7G2
J 0
(250 800);
DISPLAY 0.617021 (250 800);
PAINT AQUA (250 800);
DISPLAY INVISIBLE (250 800);
FORCEPROP 1 LAST PATH I175
J 0
(250 850);
DISPLAY 1.319149 (250 850);
PAINT ORANGE (250 850);
DISPLAY INVISIBLE (250 850);
FORCEPROP 2 LAST ROOM VDDQ_ABC_PWR_VR
J 0
(250 850);
DISPLAY 1.361702 (250 850);
PAINT ORANGE (250 850);
DISPLAY INVISIBLE (250 850);
FORCEPROP 2 LAST SEC 1
J 0
(250 925);
DISPLAY 0.680851 (250 925);
PAINT MONO (250 925);
DISPLAY INVISIBLE (250 925);
FORCEPROP 2 LAST SEC_TYPE 2626
J 0
(250 925);
DISPLAY 1.021277 (250 925);
PAINT ORANGE (250 925);
DISPLAY INVISIBLE (250 925);
FORCEADD P12V_STBY..1
(-550 1150);
FORCEPROP 3 LASTPIN (-550 1100) SIG_NAME P12V_STBY\g
J 0
(-540 1110);
DISPLAY 0.659574 (-540 1110);
PAINT MONO (-540 1110);
DISPLAY INVISIBLE (-540 1110);
FORCEPROP 1 LAST VOLTAGE 12.0V
J 0
(-595 1107);
DISPLAY 0.340426 (-595 1107);
PAINT SKYBLUE (-595 1107);
DISPLAY INVISIBLE (-595 1107);
FORCEPROP 2 LAST CDS_LIB mstr_symbols
J 0
(-550 1150);
PAINT ORANGE (-550 1150);
DISPLAY INVISIBLE (-550 1150);
FORCEPROP 1 LAST PATH I183
J 0
(-505 1152);
DISPLAY 0.340426 (-505 1152);
PAINT GREEN (-505 1152);
DISPLAY INVISIBLE (-505 1152);
FORCEPROP 1 LAST SIZE 1B
J 0
(-505 1172);
DISPLAY 0.340426 (-505 1172);
PAINT GREEN (-505 1172);
DISPLAY INVISIBLE (-505 1172);
FORCEPROP 1 LAST BODY_TYPE PLUMBING
J 0
(-595 1107);
DISPLAY 0.340426 (-595 1107);
PAINT GREEN (-595 1107);
DISPLAY INVISIBLE (-595 1107);
FORCEPROP 1 LAST HDL_POWER P12V_STBY
J 0
(-850 1025);
DISPLAY 0.872340 (-850 1025);
PAINT ORANGE (-850 1025);
DISPLAY INVISIBLE (-850 1025);
FORCEADD GND..1
(150 2525);
FORCEPROP 3 LASTPIN (150 2575) SIG_NAME GND\g
J 0
(160 2585);
DISPLAY 0.659574 (160 2585);
PAINT MONO (160 2585);
DISPLAY INVISIBLE (160 2585);
FORCEPROP 2 LAST ROOM VDDQ_ABC_PWR_VR
J 0
(-400 2600);
PAINT ORANGE (-400 2600);
DISPLAY INVISIBLE (-400 2600);
FORCEPROP 2 LAST BOM_COST MEM_VRD_PVDDQ_CD
J 0
(-175 2600);
PAINT MONO (-175 2600);
DISPLAY INVISIBLE (-175 2600);
FORCEPROP 1 LAST SIZE 1B
J 0
(225 2475);
DISPLAY 0.893617 (225 2475);
PAINT GREEN (225 2475);
DISPLAY INVISIBLE (225 2475);
FORCEPROP 2 LAST CDS_LIB mstr_symbols
J 0
(150 2525);
PAINT ORANGE (150 2525);
DISPLAY INVISIBLE (150 2525);
FORCEPROP 1 LAST PATH I187
J 0
(225 2525);
DISPLAY 0.872340 (225 2525);
PAINT AQUA (225 2525);
DISPLAY INVISIBLE (225 2525);
FORCEPROP 1 LAST VOLTAGE 0
J 0
(150 2525);
PAINT SKYBLUE (150 2525);
DISPLAY INVISIBLE (150 2525);
FORCEPROP 1 LAST BODY_TYPE PLUMBING
J 0
(105 2482);
DISPLAY 0.340426 (105 2482);
PAINT GREEN (105 2482);
DISPLAY INVISIBLE (105 2482);
FORCEPROP 1 LAST HDL_POWER GND
J 0
(150 2675);
DISPLAY 0.893617 (150 2675);
PAINT GREEN (150 2675);
DISPLAY INVISIBLE (150 2675);
FORCEADD PVDDQ_ABC..1
(-1750 3125);
FORCEPROP 3 LASTPIN (-1750 3075) SIG_NAME PVDDQ_ABC\g
J 0
(-1740 3085);
DISPLAY 0.659574 (-1740 3085);
PAINT MONO (-1740 3085);
DISPLAY INVISIBLE (-1740 3085);
FORCEPROP 1 LAST VOLTAGE 1.2V
J 0
(-1795 3082);
DISPLAY 0.340426 (-1795 3082);
PAINT SKYBLUE (-1795 3082);
DISPLAY INVISIBLE (-1795 3082);
FORCEPROP 1 LAST PATH I192
J 0
(-1700 3150);
DISPLAY 0.872340 (-1700 3150);
PAINT AQUA (-1700 3150);
DISPLAY INVISIBLE (-1700 3150);
FORCEPROP 2 LAST CDS_LIB mstr_symbols
J 0
(-1750 3125);
PAINT ORANGE (-1750 3125);
DISPLAY INVISIBLE (-1750 3125);
FORCEPROP 2 LAST BOM_COST MEM_VRD_PVDDQ_CD
J 0
(-1675 3225);
PAINT MONO (-1675 3225);
DISPLAY INVISIBLE (-1675 3225);
FORCEPROP 2 LAST ROOM VDDQ_ABC_PWR_VR
J 0
(-1500 3225);
PAINT ORANGE (-1500 3225);
DISPLAY INVISIBLE (-1500 3225);
FORCEPROP 1 LAST BODY_TYPE PLUMBING
J 0
(-1795 3082);
DISPLAY 0.340426 (-1795 3082);
PAINT GREEN (-1795 3082);
DISPLAY INVISIBLE (-1795 3082);
FORCEPROP 1 LAST HDL_POWER PVDDQ_ABC
J 1
(-1750 3175);
DISPLAY 0.872340 (-1750 3175);
PAINT GREEN (-1750 3175);
DISPLAY INVISIBLE (-1750 3175);
FORCEADD PVDDQ_ABC..1
(2925 1275);
FORCEPROP 3 LASTPIN (2925 1225) SIG_NAME PVDDQ_ABC\g
J 0
(2935 1235);
DISPLAY 0.659574 (2935 1235);
PAINT MONO (2935 1235);
DISPLAY INVISIBLE (2935 1235);
FORCEPROP 1 LAST VOLTAGE 1.2V
J 0
(2880 1232);
DISPLAY 0.340426 (2880 1232);
PAINT SKYBLUE (2880 1232);
DISPLAY INVISIBLE (2880 1232);
FORCEPROP 2 LAST CDS_LIB mstr_symbols
J 0
(2925 1275);
PAINT ORANGE (2925 1275);
DISPLAY INVISIBLE (2925 1275);
FORCEPROP 1 LAST PATH I201
J 0
(2975 1300);
DISPLAY 0.872340 (2975 1300);
PAINT AQUA (2975 1300);
DISPLAY INVISIBLE (2975 1300);
FORCEPROP 1 LAST BODY_TYPE PLUMBING
J 0
(2880 1232);
DISPLAY 0.340426 (2880 1232);
PAINT GREEN (2880 1232);
DISPLAY INVISIBLE (2880 1232);
FORCEPROP 1 LAST HDL_POWER PVDDQ_ABC
J 1
(2925 1325);
DISPLAY 0.872340 (2925 1325);
PAINT GREEN (2925 1325);
DISPLAY INVISIBLE (2925 1325);
FORCEADD GND..1
(3575 625);
FORCEPROP 3 LASTPIN (3575 675) SIG_NAME GND\g
J 0
(3585 685);
DISPLAY 0.659574 (3585 685);
PAINT MONO (3585 685);
DISPLAY INVISIBLE (3585 685);
FORCEPROP 2 LAST BOM_COST MEM_VRD_PVDDQ_CD
J 0
(3250 700);
PAINT MONO (3250 700);
DISPLAY INVISIBLE (3250 700);
FORCEPROP 2 LAST CDS_LIB mstr_symbols
J 0
(3575 625);
PAINT ORANGE (3575 625);
DISPLAY INVISIBLE (3575 625);
FORCEPROP 1 LAST VOLTAGE 0
J 0
(3575 625);
PAINT SKYBLUE (3575 625);
DISPLAY INVISIBLE (3575 625);
FORCEPROP 1 LAST SIZE 1B
J 0
(3650 575);
DISPLAY 0.893617 (3650 575);
PAINT GREEN (3650 575);
DISPLAY INVISIBLE (3650 575);
FORCEPROP 1 LAST PATH I203
J 0
(3650 625);
DISPLAY 0.872340 (3650 625);
PAINT AQUA (3650 625);
DISPLAY INVISIBLE (3650 625);
FORCEPROP 1 LAST BODY_TYPE PLUMBING
J 0
(3530 582);
DISPLAY 0.340426 (3530 582);
PAINT GREEN (3530 582);
DISPLAY INVISIBLE (3530 582);
FORCEPROP 1 LAST HDL_POWER GND
J 0
(3575 775);
DISPLAY 0.893617 (3575 775);
PAINT GREEN (3575 775);
DISPLAY INVISIBLE (3575 775);
FORCEADD CAP_A..1
(2925 1000);
FORCEPROP 1 LAST LOCATION C5F2
J 0
(2975 1100);
DISPLAY 0.617021 (2975 1100);
PAINT AQUA (2975 1100);
FORCEPROP 1 LAST VOLTAGE 4V
J 0
(2975 1000);
DISPLAY 0.617021 (2975 1000);
PAINT SKYBLUE (2975 1000);
FORCEPROP 1 LASTPIN (2925 1100) $PN 1
J 0
(2935 1080);
DISPLAY 0.617021 (2935 1080);
PAINT ORANGE (2935 1080);
FORCEPROP 1 LASTPIN (2925 900) $PN 2
J 0
(2935 880);
DISPLAY 0.617021 (2935 880);
PAINT ORANGE (2935 880);
FORCEPROP 1 LAST VALUE 47UF
J 0
(2975 1050);
DISPLAY 0.617021 (2975 1050);
PAINT SKYBLUE (2975 1050);
FORCEPROP 1 LAST TOLERANCE 20%
J 0
(2975 950);
DISPLAY 0.617021 (2975 950);
PAINT SKYBLUE (2975 950);
FORCEPROP 1 LAST MATERIAL X5R
J 0
(2975 900);
DISPLAY 0.617021 (2975 900);
PAINT SKYBLUE (2975 900);
FORCEPROP 1 LAST PART_NUMBER 602433-106
J 0
(2975 850);
DISPLAY 0.617021 (2975 850);
PAINT BLUE (2975 850);
FORCEPROP 1 LAST PACK_TYPE 0603V
J 0
(2975 800);
DISPLAY 0.617021 (2975 800);
PAINT SKYBLUE (2975 800);
FORCEPROP 0 LAST GROUP PWR_MLCC_CAP
J 0
(2981 762);
DISPLAY 0.638298 (2981 762);
PAINT BROWN (2981 762);
DISPLAY BOTH (2981 762);
FORCEPROP 0 LAST BOM_SS NOPOP
J 0
(2925 700);
DISPLAY 0.638298 (2925 700);
PAINT BROWN (2925 700);
DISPLAY BOTH (2925 700);
FORCEPROP 1 LAST PATH I205
J 0
(2975 1150);
DISPLAY 0.978723 (2975 1150);
PAINT WHITE (2975 1150);
DISPLAY INVISIBLE (2975 1150);
FORCEPROP 2 LAST CDS_LOCATION C5F2
J 0
(2975 1100);
DISPLAY 0.617021 (2975 1100);
PAINT AQUA (2975 1100);
DISPLAY INVISIBLE (2975 1100);
FORCEPROP 2 LAST CDS_SEC 1
J 0
(2975 1150);
PAINT ORANGE (2975 1150);
DISPLAY INVISIBLE (2975 1150);
FORCEPROP 2 LAST SEC_TYPE 0603V
J 0
(2975 1200);
DISPLAY 1.021277 (2975 1200);
PAINT ORANGE (2975 1200);
DISPLAY INVISIBLE (2975 1200);
FORCEPROP 2 LAST SEC 1
J 0
(2975 1200);
DISPLAY 0.680851 (2975 1200);
PAINT MONO (2975 1200);
DISPLAY INVISIBLE (2975 1200);
FORCEPROP 2 LAST CDS_LIB dev_discrete
J 0
(2925 1000);
PAINT ORANGE (2925 1000);
DISPLAY INVISIBLE (2925 1000);
FORCEADD CAP_A..1
(3275 1000);
FORCEPROP 0 LAST BOM_SS NOPOP
J 0
(3325 675);
DISPLAY 0.638298 (3325 675);
PAINT BROWN (3325 675);
DISPLAY BOTH (3325 675);
FORCEPROP 1 LAST VOLTAGE 4V
J 0
(3325 1000);
DISPLAY 0.617021 (3325 1000);
PAINT SKYBLUE (3325 1000);
FORCEPROP 1 LAST TOLERANCE 20%
J 0
(3325 950);
DISPLAY 0.617021 (3325 950);
PAINT SKYBLUE (3325 950);
FORCEPROP 1 LASTPIN (3275 900) $PN 2
J 0
(3285 880);
DISPLAY 0.617021 (3285 880);
PAINT ORANGE (3285 880);
FORCEPROP 1 LASTPIN (3275 1100) $PN 1
J 0
(3285 1080);
DISPLAY 0.617021 (3285 1080);
PAINT ORANGE (3285 1080);
FORCEPROP 1 LAST LOCATION C5F1
J 0
(3325 1100);
DISPLAY 0.617021 (3325 1100);
PAINT AQUA (3325 1100);
FORCEPROP 1 LAST VALUE 47UF
J 0
(3325 1050);
DISPLAY 0.617021 (3325 1050);
PAINT SKYBLUE (3325 1050);
FORCEPROP 1 LAST MATERIAL X5R
J 0
(3325 900);
DISPLAY 0.617021 (3325 900);
PAINT SKYBLUE (3325 900);
FORCEPROP 1 LAST PACK_TYPE 0603V
J 0
(3325 800);
DISPLAY 0.617021 (3325 800);
PAINT SKYBLUE (3325 800);
FORCEPROP 0 LAST GROUP PWR_MLCC_CAP
J 0
(3331 712);
DISPLAY 0.638298 (3331 712);
PAINT BROWN (3331 712);
DISPLAY BOTH (3331 712);
FORCEPROP 1 LAST PART_NUMBER 602433-106
J 0
(3325 850);
DISPLAY 0.617021 (3325 850);
PAINT BLUE (3325 850);
FORCEPROP 2 LAST CDS_LIB dev_discrete
J 0
(3275 1000);
PAINT ORANGE (3275 1000);
DISPLAY INVISIBLE (3275 1000);
FORCEPROP 2 LAST CDS_LOCATION C5F1
J 0
(3325 1100);
DISPLAY 0.617021 (3325 1100);
PAINT AQUA (3325 1100);
DISPLAY INVISIBLE (3325 1100);
FORCEPROP 2 LAST CDS_SEC 1
J 0
(3325 1150);
PAINT ORANGE (3325 1150);
DISPLAY INVISIBLE (3325 1150);
FORCEPROP 2 LAST SEC_TYPE 0603V
J 0
(3325 1200);
DISPLAY 1.021277 (3325 1200);
PAINT ORANGE (3325 1200);
DISPLAY INVISIBLE (3325 1200);
FORCEPROP 2 LAST SEC 1
J 0
(3325 1200);
DISPLAY 0.680851 (3325 1200);
PAINT MONO (3325 1200);
DISPLAY INVISIBLE (3325 1200);
FORCEPROP 1 LAST PATH I206
J 0
(3325 1150);
DISPLAY 0.978723 (3325 1150);
PAINT WHITE (3325 1150);
DISPLAY INVISIBLE (3325 1150);
FORCEADD CAP_A..1
(3675 1000);
FORCEPROP 1 LAST VOLTAGE 4V
J 0
(3725 1000);
DISPLAY 0.617021 (3725 1000);
PAINT SKYBLUE (3725 1000);
FORCEPROP 1 LAST TOLERANCE 20%
J 0
(3725 950);
DISPLAY 0.617021 (3725 950);
PAINT SKYBLUE (3725 950);
FORCEPROP 1 LAST MATERIAL X5R
J 0
(3725 900);
DISPLAY 0.617021 (3725 900);
PAINT SKYBLUE (3725 900);
FORCEPROP 1 LAST VALUE 47UF
J 0
(3725 1050);
DISPLAY 0.617021 (3725 1050);
PAINT SKYBLUE (3725 1050);
FORCEPROP 1 LASTPIN (3675 900) $PN 2
J 0
(3685 880);
DISPLAY 0.617021 (3685 880);
PAINT ORANGE (3685 880);
FORCEPROP 1 LAST PACK_TYPE 0603V
J 0
(3725 800);
DISPLAY 0.617021 (3725 800);
PAINT SKYBLUE (3725 800);
FORCEPROP 1 LASTPIN (3675 1100) $PN 1
J 0
(3685 1080);
DISPLAY 0.617021 (3685 1080);
PAINT ORANGE (3685 1080);
FORCEPROP 1 LAST LOCATION C5G10
J 0
(3725 1100);
DISPLAY 0.617021 (3725 1100);
PAINT AQUA (3725 1100);
FORCEPROP 0 LAST BOM_SS NOPOP
J 0
(3850 725);
DISPLAY 0.638298 (3850 725);
PAINT BROWN (3850 725);
DISPLAY BOTH (3850 725);
FORCEPROP 0 LAST GROUP PWR_MLCC_CAP
J 0
(3731 762);
DISPLAY 0.638298 (3731 762);
PAINT BROWN (3731 762);
DISPLAY BOTH (3731 762);
FORCEPROP 1 LAST PART_NUMBER 602433-106
J 0
(3725 850);
DISPLAY 0.617021 (3725 850);
PAINT BLUE (3725 850);
FORCEPROP 2 LAST CDS_LIB dev_discrete
J 0
(3675 1000);
PAINT ORANGE (3675 1000);
DISPLAY INVISIBLE (3675 1000);
FORCEPROP 2 LAST CDS_LOCATION C5G10
J 0
(3725 1100);
DISPLAY 0.617021 (3725 1100);
PAINT AQUA (3725 1100);
DISPLAY INVISIBLE (3725 1100);
FORCEPROP 2 LAST CDS_SEC 1
J 0
(3725 1150);
PAINT ORANGE (3725 1150);
DISPLAY INVISIBLE (3725 1150);
FORCEPROP 2 LAST SEC_TYPE 0603V
J 0
(3725 1200);
DISPLAY 1.021277 (3725 1200);
PAINT ORANGE (3725 1200);
DISPLAY INVISIBLE (3725 1200);
FORCEPROP 2 LAST SEC 1
J 0
(3725 1200);
DISPLAY 0.680851 (3725 1200);
PAINT MONO (3725 1200);
DISPLAY INVISIBLE (3725 1200);
FORCEPROP 1 LAST PATH I207
J 0
(3725 1150);
DISPLAY 0.978723 (3725 1150);
PAINT WHITE (3725 1150);
DISPLAY INVISIBLE (3725 1150);
FORCEADD CAP_A..1
(4000 1725);
FORCEPROP 1 LASTPIN (4000 1625) $PN 2
J 0
(4010 1605);
DISPLAY 0.617021 (4010 1605);
PAINT ORANGE (4010 1605);
FORCEPROP 1 LAST VOLTAGE 4V
J 0
(4050 1725);
DISPLAY 0.617021 (4050 1725);
PAINT SKYBLUE (4050 1725);
FORCEPROP 1 LAST TOLERANCE 20%
J 0
(4050 1675);
DISPLAY 0.617021 (4050 1675);
PAINT SKYBLUE (4050 1675);
FORCEPROP 1 LAST VALUE 47UF
J 0
(4050 1775);
DISPLAY 0.617021 (4050 1775);
PAINT SKYBLUE (4050 1775);
FORCEPROP 1 LASTPIN (4000 1825) $PN 1
J 0
(4010 1805);
DISPLAY 0.617021 (4010 1805);
PAINT ORANGE (4010 1805);
FORCEPROP 1 LAST LOCATION C5T2
J 0
(4050 1825);
DISPLAY 0.617021 (4050 1825);
PAINT AQUA (4050 1825);
FORCEPROP 1 LAST MATERIAL X5R
J 0
(4050 1625);
DISPLAY 0.617021 (4050 1625);
PAINT SKYBLUE (4050 1625);
FORCEPROP 1 LAST PART_NUMBER 602433-106
J 0
(4050 1575);
DISPLAY 0.617021 (4050 1575);
PAINT BLUE (4050 1575);
FORCEPROP 1 LAST PACK_TYPE 0603V
J 0
(4050 1525);
DISPLAY 0.617021 (4050 1525);
PAINT SKYBLUE (4050 1525);
FORCEPROP 0 LAST BOM_SS NOPOP
J 0
(4050 1375);
DISPLAY 0.638298 (4050 1375);
PAINT BROWN (4050 1375);
DISPLAY BOTH (4050 1375);
FORCEPROP 0 LAST GROUP PWR_MLCC_CAP
J 0
(4056 1437);
DISPLAY 0.638298 (4056 1437);
PAINT BROWN (4056 1437);
DISPLAY BOTH (4056 1437);
FORCEPROP 2 LAST CDS_LIB dev_discrete
J 0
(4000 1725);
PAINT ORANGE (4000 1725);
DISPLAY INVISIBLE (4000 1725);
FORCEPROP 1 LAST PATH I208
J 0
(4050 1875);
DISPLAY 0.978723 (4050 1875);
PAINT WHITE (4050 1875);
DISPLAY INVISIBLE (4050 1875);
FORCEPROP 2 LAST SEC 1
J 0
(4050 1925);
DISPLAY 0.680851 (4050 1925);
PAINT MONO (4050 1925);
DISPLAY INVISIBLE (4050 1925);
FORCEPROP 2 LAST SEC_TYPE 0603V
J 0
(4050 1925);
DISPLAY 1.021277 (4050 1925);
PAINT ORANGE (4050 1925);
DISPLAY INVISIBLE (4050 1925);
FORCEPROP 2 LAST CDS_SEC 1
J 0
(4050 1875);
PAINT ORANGE (4050 1875);
DISPLAY INVISIBLE (4050 1875);
FORCEPROP 2 LAST CDS_LOCATION C5T2
J 0
(4050 1825);
DISPLAY 0.617021 (4050 1825);
PAINT AQUA (4050 1825);
DISPLAY INVISIBLE (4050 1825);
FORCEADD CAP_A..1
(4350 1725);
FORCEPROP 1 LAST PART_NUMBER 602433-106
J 0
(4400 1575);
DISPLAY 0.617021 (4400 1575);
PAINT BLUE (4400 1575);
FORCEPROP 1 LAST MATERIAL X5R
J 0
(4400 1625);
DISPLAY 0.617021 (4400 1625);
PAINT SKYBLUE (4400 1625);
FORCEPROP 1 LAST PACK_TYPE 0603V
J 0
(4400 1525);
DISPLAY 0.617021 (4400 1525);
PAINT SKYBLUE (4400 1525);
FORCEPROP 1 LASTPIN (4350 1625) $PN 2
J 0
(4360 1605);
DISPLAY 0.617021 (4360 1605);
PAINT ORANGE (4360 1605);
FORCEPROP 1 LAST VALUE 47UF
J 0
(4400 1775);
DISPLAY 0.617021 (4400 1775);
PAINT SKYBLUE (4400 1775);
FORCEPROP 1 LASTPIN (4350 1825) $PN 1
J 0
(4360 1805);
DISPLAY 0.617021 (4360 1805);
PAINT ORANGE (4360 1805);
FORCEPROP 1 LAST LOCATION C5U11
J 0
(4400 1825);
DISPLAY 0.617021 (4400 1825);
PAINT AQUA (4400 1825);
FORCEPROP 1 LAST TOLERANCE 20%
J 0
(4400 1675);
DISPLAY 0.617021 (4400 1675);
PAINT SKYBLUE (4400 1675);
FORCEPROP 1 LAST VOLTAGE 4V
J 0
(4400 1725);
DISPLAY 0.617021 (4400 1725);
PAINT SKYBLUE (4400 1725);
FORCEPROP 0 LAST BOM_SS NOPOP
J 0
(4425 1400);
DISPLAY 0.638298 (4425 1400);
PAINT BROWN (4425 1400);
DISPLAY BOTH (4425 1400);
FORCEPROP 0 LAST GROUP PWR_MLCC_CAP
J 0
(4406 1487);
DISPLAY 0.638298 (4406 1487);
PAINT BROWN (4406 1487);
DISPLAY BOTH (4406 1487);
FORCEPROP 2 LAST CDS_LIB dev_discrete
J 0
(4350 1725);
PAINT ORANGE (4350 1725);
DISPLAY INVISIBLE (4350 1725);
FORCEPROP 2 LAST CDS_LOCATION C5U11
J 0
(4400 1825);
DISPLAY 0.617021 (4400 1825);
PAINT AQUA (4400 1825);
DISPLAY INVISIBLE (4400 1825);
FORCEPROP 2 LAST CDS_SEC 1
J 0
(4400 1875);
PAINT ORANGE (4400 1875);
DISPLAY INVISIBLE (4400 1875);
FORCEPROP 2 LAST SEC_TYPE 0603V
J 0
(4400 1925);
DISPLAY 1.021277 (4400 1925);
PAINT ORANGE (4400 1925);
DISPLAY INVISIBLE (4400 1925);
FORCEPROP 2 LAST SEC 1
J 0
(4400 1925);
DISPLAY 0.680851 (4400 1925);
PAINT MONO (4400 1925);
DISPLAY INVISIBLE (4400 1925);
FORCEPROP 1 LAST PATH I209
J 0
(4400 1875);
DISPLAY 0.978723 (4400 1875);
PAINT WHITE (4400 1875);
DISPLAY INVISIBLE (4400 1875);
FORCEADD CAP_A..1
(4750 1725);
FORCEPROP 1 LASTPIN (4750 1825) $PN 1
J 0
(4760 1805);
DISPLAY 0.617021 (4760 1805);
PAINT ORANGE (4760 1805);
FORCEPROP 1 LAST PART_NUMBER 602433-106
J 0
(4800 1575);
DISPLAY 0.617021 (4800 1575);
PAINT BLUE (4800 1575);
FORCEPROP 1 LASTPIN (4750 1625) $PN 2
J 0
(4760 1605);
DISPLAY 0.617021 (4760 1605);
PAINT ORANGE (4760 1605);
FORCEPROP 1 LAST MATERIAL X5R
J 0
(4800 1625);
DISPLAY 0.617021 (4800 1625);
PAINT SKYBLUE (4800 1625);
FORCEPROP 1 LAST VOLTAGE 4V
J 0
(4800 1725);
DISPLAY 0.617021 (4800 1725);
PAINT SKYBLUE (4800 1725);
FORCEPROP 1 LAST VALUE 47UF
J 0
(4800 1775);
DISPLAY 0.617021 (4800 1775);
PAINT SKYBLUE (4800 1775);
FORCEPROP 1 LAST LOCATION C5T13
J 0
(4800 1825);
DISPLAY 0.617021 (4800 1825);
PAINT AQUA (4800 1825);
FORCEPROP 0 LAST BOM_SS NOPOP
J 0
(4800 1375);
DISPLAY 0.638298 (4800 1375);
PAINT BROWN (4800 1375);
DISPLAY BOTH (4800 1375);
FORCEPROP 0 LAST GROUP PWR_MLCC_CAP
J 0
(4806 1437);
DISPLAY 0.638298 (4806 1437);
PAINT BROWN (4806 1437);
DISPLAY BOTH (4806 1437);
FORCEPROP 1 LAST PACK_TYPE 0603V
J 0
(4800 1525);
DISPLAY 0.617021 (4800 1525);
PAINT SKYBLUE (4800 1525);
FORCEPROP 1 LAST TOLERANCE 20%
J 0
(4800 1675);
DISPLAY 0.617021 (4800 1675);
PAINT SKYBLUE (4800 1675);
FORCEPROP 2 LAST CDS_LIB dev_discrete
J 0
(4750 1725);
PAINT ORANGE (4750 1725);
DISPLAY INVISIBLE (4750 1725);
FORCEPROP 1 LAST PATH I210
J 0
(4800 1875);
DISPLAY 0.978723 (4800 1875);
PAINT WHITE (4800 1875);
DISPLAY INVISIBLE (4800 1875);
FORCEPROP 2 LAST SEC 1
J 0
(4800 1925);
DISPLAY 0.680851 (4800 1925);
PAINT MONO (4800 1925);
DISPLAY INVISIBLE (4800 1925);
FORCEPROP 2 LAST SEC_TYPE 0603V
J 0
(4800 1925);
DISPLAY 1.021277 (4800 1925);
PAINT ORANGE (4800 1925);
DISPLAY INVISIBLE (4800 1925);
FORCEPROP 2 LAST CDS_SEC 1
J 0
(4800 1875);
PAINT ORANGE (4800 1875);
DISPLAY INVISIBLE (4800 1875);
FORCEPROP 2 LAST CDS_LOCATION C5T13
J 0
(4800 1825);
DISPLAY 0.617021 (4800 1825);
PAINT AQUA (4800 1825);
DISPLAY INVISIBLE (4800 1825);
FORCEADD CAP_A..1
(3650 1725);
FORCEPROP 1 LASTPIN (3650 1825) $PN 1
J 0
(3660 1805);
DISPLAY 0.617021 (3660 1805);
PAINT ORANGE (3660 1805);
FORCEPROP 1 LAST MATERIAL X5R
J 0
(3700 1625);
DISPLAY 0.617021 (3700 1625);
PAINT SKYBLUE (3700 1625);
FORCEPROP 1 LAST PACK_TYPE 0603V
J 0
(3700 1525);
DISPLAY 0.617021 (3700 1525);
PAINT SKYBLUE (3700 1525);
FORCEPROP 1 LAST PART_NUMBER 602433-106
J 0
(3700 1575);
DISPLAY 0.617021 (3700 1575);
PAINT BLUE (3700 1575);
FORCEPROP 1 LASTPIN (3650 1625) $PN 2
J 0
(3660 1605);
DISPLAY 0.617021 (3660 1605);
PAINT ORANGE (3660 1605);
FORCEPROP 1 LAST TOLERANCE 20%
J 0
(3700 1675);
DISPLAY 0.617021 (3700 1675);
PAINT SKYBLUE (3700 1675);
FORCEPROP 1 LAST VOLTAGE 4V
J 0
(3700 1725);
DISPLAY 0.617021 (3700 1725);
PAINT SKYBLUE (3700 1725);
FORCEPROP 1 LAST VALUE 47UF
J 0
(3700 1775);
DISPLAY 0.617021 (3700 1775);
PAINT SKYBLUE (3700 1775);
FORCEPROP 1 LAST LOCATION C5T4
J 0
(3700 1825);
DISPLAY 0.617021 (3700 1825);
PAINT AQUA (3700 1825);
FORCEPROP 0 LAST GROUP PWR_MLCC_CAP
J 0
(3706 1487);
DISPLAY 0.638298 (3706 1487);
PAINT BROWN (3706 1487);
DISPLAY BOTH (3706 1487);
FORCEPROP 0 LAST BOM_SS 078.1061T.M001
J 0
(3700 1325);
DISPLAY 0.638298 (3700 1325);
PAINT BROWN (3700 1325);
DISPLAY BOTH (3700 1325);
FORCEPROP 2 LAST CDS_LIB dev_discrete
J 0
(3650 1725);
PAINT ORANGE (3650 1725);
DISPLAY INVISIBLE (3650 1725);
FORCEPROP 1 LAST PATH I211
J 0
(3700 1875);
DISPLAY 0.978723 (3700 1875);
PAINT WHITE (3700 1875);
DISPLAY INVISIBLE (3700 1875);
FORCEPROP 2 LAST SEC 1
J 0
(3700 1925);
DISPLAY 0.680851 (3700 1925);
PAINT MONO (3700 1925);
DISPLAY INVISIBLE (3700 1925);
FORCEPROP 2 LAST SEC_TYPE 0603V
J 0
(3700 1925);
DISPLAY 1.021277 (3700 1925);
PAINT ORANGE (3700 1925);
DISPLAY INVISIBLE (3700 1925);
FORCEPROP 2 LAST CDS_SEC 1
J 0
(3700 1875);
PAINT ORANGE (3700 1875);
DISPLAY INVISIBLE (3700 1875);
FORCEPROP 2 LAST CDS_LOCATION C5T4
J 0
(3700 1825);
DISPLAY 0.617021 (3700 1825);
PAINT AQUA (3700 1825);
DISPLAY INVISIBLE (3700 1825);
FORCEADD CAP_A..1
(3250 1725);
FORCEPROP 1 LAST TOLERANCE 20%
J 0
(3300 1675);
DISPLAY 0.617021 (3300 1675);
PAINT SKYBLUE (3300 1675);
FORCEPROP 1 LAST MATERIAL X5R
J 0
(3300 1625);
DISPLAY 0.617021 (3300 1625);
PAINT SKYBLUE (3300 1625);
FORCEPROP 1 LAST PART_NUMBER 602433-106
J 0
(3300 1575);
DISPLAY 0.617021 (3300 1575);
PAINT BLUE (3300 1575);
FORCEPROP 0 LAST BOM_SS NOPOP
J 0
(3300 1375);
DISPLAY 0.638298 (3300 1375);
PAINT BROWN (3300 1375);
DISPLAY BOTH (3300 1375);
FORCEPROP 0 LAST GROUP PWR_MLCC_CAP
J 0
(3306 1437);
DISPLAY 0.638298 (3306 1437);
PAINT BROWN (3306 1437);
DISPLAY BOTH (3306 1437);
FORCEPROP 1 LAST VOLTAGE 4V
J 0
(3300 1725);
DISPLAY 0.617021 (3300 1725);
PAINT SKYBLUE (3300 1725);
FORCEPROP 1 LASTPIN (3250 1825) $PN 1
J 0
(3260 1805);
DISPLAY 0.617021 (3260 1805);
PAINT ORANGE (3260 1805);
FORCEPROP 1 LASTPIN (3250 1625) $PN 2
J 0
(3260 1605);
DISPLAY 0.617021 (3260 1605);
PAINT ORANGE (3260 1605);
FORCEPROP 1 LAST PACK_TYPE 0603V
J 0
(3300 1525);
DISPLAY 0.617021 (3300 1525);
PAINT SKYBLUE (3300 1525);
FORCEPROP 1 LAST LOCATION C5T1
J 0
(3300 1825);
DISPLAY 0.617021 (3300 1825);
PAINT AQUA (3300 1825);
FORCEPROP 1 LAST VALUE 47UF
J 0
(3300 1775);
DISPLAY 0.617021 (3300 1775);
PAINT SKYBLUE (3300 1775);
FORCEPROP 2 LAST CDS_LIB dev_discrete
J 0
(3250 1725);
PAINT ORANGE (3250 1725);
DISPLAY INVISIBLE (3250 1725);
FORCEPROP 1 LAST PATH I212
J 0
(3300 1875);
DISPLAY 0.978723 (3300 1875);
PAINT WHITE (3300 1875);
DISPLAY INVISIBLE (3300 1875);
FORCEPROP 2 LAST SEC 1
J 0
(3300 1925);
DISPLAY 0.680851 (3300 1925);
PAINT MONO (3300 1925);
DISPLAY INVISIBLE (3300 1925);
FORCEPROP 2 LAST SEC_TYPE 0603V
J 0
(3300 1925);
DISPLAY 1.021277 (3300 1925);
PAINT ORANGE (3300 1925);
DISPLAY INVISIBLE (3300 1925);
FORCEPROP 2 LAST CDS_SEC 1
J 0
(3300 1875);
PAINT ORANGE (3300 1875);
DISPLAY INVISIBLE (3300 1875);
FORCEPROP 2 LAST CDS_LOCATION C5T1
J 0
(3300 1825);
DISPLAY 0.617021 (3300 1825);
PAINT AQUA (3300 1825);
DISPLAY INVISIBLE (3300 1825);
FORCEADD CAP_A..1
(2900 1725);
FORCEPROP 0 LAST BOM_SS NOPOP
J 0
(2950 1425);
DISPLAY 0.638298 (2950 1425);
PAINT BROWN (2950 1425);
DISPLAY BOTH (2950 1425);
FORCEPROP 0 LAST GROUP PWR_MLCC_CAP
J 0
(2956 1487);
DISPLAY 0.638298 (2956 1487);
PAINT BROWN (2956 1487);
DISPLAY BOTH (2956 1487);
FORCEPROP 1 LAST PART_NUMBER 602433-106
J 0
(2950 1575);
DISPLAY 0.617021 (2950 1575);
PAINT BLUE (2950 1575);
FORCEPROP 1 LAST VALUE 47UF
J 0
(2950 1775);
DISPLAY 0.617021 (2950 1775);
PAINT SKYBLUE (2950 1775);
FORCEPROP 1 LAST TOLERANCE 20%
J 0
(2950 1675);
DISPLAY 0.617021 (2950 1675);
PAINT SKYBLUE (2950 1675);
FORCEPROP 1 LAST VOLTAGE 4V
J 0
(2950 1725);
DISPLAY 0.617021 (2950 1725);
PAINT SKYBLUE (2950 1725);
FORCEPROP 1 LAST MATERIAL X5R
J 0
(2950 1625);
DISPLAY 0.617021 (2950 1625);
PAINT SKYBLUE (2950 1625);
FORCEPROP 1 LASTPIN (2900 1625) $PN 2
J 0
(2910 1605);
DISPLAY 0.617021 (2910 1605);
PAINT ORANGE (2910 1605);
FORCEPROP 1 LAST PACK_TYPE 0603V
J 0
(2950 1525);
DISPLAY 0.617021 (2950 1525);
PAINT SKYBLUE (2950 1525);
FORCEPROP 1 LAST LOCATION C5G19
J 0
(2950 1825);
DISPLAY 0.617021 (2950 1825);
PAINT AQUA (2950 1825);
FORCEPROP 1 LASTPIN (2900 1825) $PN 1
J 0
(2910 1805);
DISPLAY 0.617021 (2910 1805);
PAINT ORANGE (2910 1805);
FORCEPROP 2 LAST CDS_LIB dev_discrete
J 0
(2900 1725);
PAINT ORANGE (2900 1725);
DISPLAY INVISIBLE (2900 1725);
FORCEPROP 1 LAST PATH I213
J 0
(2950 1875);
DISPLAY 0.978723 (2950 1875);
PAINT WHITE (2950 1875);
DISPLAY INVISIBLE (2950 1875);
FORCEPROP 2 LAST SEC 1
J 0
(2950 1925);
DISPLAY 0.680851 (2950 1925);
PAINT MONO (2950 1925);
DISPLAY INVISIBLE (2950 1925);
FORCEPROP 2 LAST SEC_TYPE 0603V
J 0
(2950 1925);
DISPLAY 1.021277 (2950 1925);
PAINT ORANGE (2950 1925);
DISPLAY INVISIBLE (2950 1925);
FORCEPROP 2 LAST CDS_SEC 1
J 0
(2950 1875);
PAINT ORANGE (2950 1875);
DISPLAY INVISIBLE (2950 1875);
FORCEPROP 2 LAST CDS_LOCATION C5G19
J 0
(2950 1825);
DISPLAY 0.617021 (2950 1825);
PAINT AQUA (2950 1825);
DISPLAY INVISIBLE (2950 1825);
FORCEADD PVDDQ_ABC..1
(-900 3125);
FORCEPROP 3 LASTPIN (-900 3075) SIG_NAME PVDDQ_ABC\g
J 0
(-890 3085);
DISPLAY 0.659574 (-890 3085);
PAINT MONO (-890 3085);
DISPLAY INVISIBLE (-890 3085);
FORCEPROP 2 LAST BOM_COST MEM_VRD_PVDDQ_CD
J 0
(-825 3225);
PAINT MONO (-825 3225);
DISPLAY INVISIBLE (-825 3225);
FORCEPROP 2 LAST CDS_LIB mstr_symbols
J 0
(-900 3125);
PAINT ORANGE (-900 3125);
DISPLAY INVISIBLE (-900 3125);
FORCEPROP 1 LAST PATH I214
J 0
(-850 3150);
DISPLAY 0.872340 (-850 3150);
PAINT AQUA (-850 3150);
DISPLAY INVISIBLE (-850 3150);
FORCEPROP 2 LAST ROOM VDDQ_ABC_PWR_VR
J 0
(-650 3225);
PAINT ORANGE (-650 3225);
DISPLAY INVISIBLE (-650 3225);
FORCEPROP 1 LAST VOLTAGE 1.2V
J 0
(-945 3082);
DISPLAY 0.340426 (-945 3082);
PAINT SKYBLUE (-945 3082);
DISPLAY INVISIBLE (-945 3082);
FORCEPROP 1 LAST BODY_TYPE PLUMBING
J 0
(-945 3082);
DISPLAY 0.340426 (-945 3082);
PAINT GREEN (-945 3082);
DISPLAY INVISIBLE (-945 3082);
FORCEPROP 1 LAST HDL_POWER PVDDQ_ABC
J 1
(-900 3175);
DISPLAY 0.872340 (-900 3175);
PAINT GREEN (-900 3175);
DISPLAY INVISIBLE (-900 3175);
FORCEADD GND..1
(-1400 2500);
FORCEPROP 3 LASTPIN (-1400 2550) SIG_NAME GND\g
J 0
(-1390 2560);
DISPLAY 0.659574 (-1390 2560);
PAINT MONO (-1390 2560);
DISPLAY INVISIBLE (-1390 2560);
FORCEPROP 2 LAST ROOM VDDQ_ABC_PWR_VR
J 0
(-1950 2575);
PAINT ORANGE (-1950 2575);
DISPLAY INVISIBLE (-1950 2575);
FORCEPROP 2 LAST BOM_COST MEM_VRD_PVDDQ_CD
J 0
(-1725 2575);
PAINT MONO (-1725 2575);
DISPLAY INVISIBLE (-1725 2575);
FORCEPROP 1 LAST SIZE 1B
J 0
(-1325 2450);
DISPLAY 0.893617 (-1325 2450);
PAINT GREEN (-1325 2450);
DISPLAY INVISIBLE (-1325 2450);
FORCEPROP 2 LAST CDS_LIB mstr_symbols
J 0
(-1400 2500);
PAINT ORANGE (-1400 2500);
DISPLAY INVISIBLE (-1400 2500);
FORCEPROP 1 LAST PATH I215
J 0
(-1325 2500);
DISPLAY 0.872340 (-1325 2500);
PAINT AQUA (-1325 2500);
DISPLAY INVISIBLE (-1325 2500);
FORCEPROP 1 LAST VOLTAGE 0
J 0
(-1400 2500);
PAINT SKYBLUE (-1400 2500);
DISPLAY INVISIBLE (-1400 2500);
FORCEPROP 1 LAST BODY_TYPE PLUMBING
J 0
(-1445 2457);
DISPLAY 0.340426 (-1445 2457);
PAINT GREEN (-1445 2457);
DISPLAY INVISIBLE (-1445 2457);
FORCEPROP 1 LAST HDL_POWER GND
J 0
(-1400 2650);
DISPLAY 0.893617 (-1400 2650);
PAINT GREEN (-1400 2650);
DISPLAY INVISIBLE (-1400 2650);
FORCEADD PVDDQ_ABC..1
(-1825 300);
FORCEPROP 3 LASTPIN (-1825 250) SIG_NAME PVDDQ_ABC\g
J 0
(-1815 260);
DISPLAY 0.659574 (-1815 260);
PAINT MONO (-1815 260);
DISPLAY INVISIBLE (-1815 260);
FORCEPROP 2 LAST ROOM VDDQ_ABC_PWR_VR
J 0
(-1825 400);
DISPLAY 1.936170 (-1825 400);
PAINT ORANGE (-1825 400);
DISPLAY INVISIBLE (-1825 400);
FORCEPROP 2 LAST CDS_LIB mstr_symbols
J 0
(-1825 300);
PAINT ORANGE (-1825 300);
DISPLAY INVISIBLE (-1825 300);
FORCEPROP 2 LAST BOM_COST PROC_SOCKET 
J 0
(-1825 400);
DISPLAY 1.446809 (-1825 400);
PAINT MONO (-1825 400);
DISPLAY INVISIBLE (-1825 400);
FORCEPROP 1 LAST VOLTAGE 1.2V
J 0
(-1870 257);
DISPLAY 0.340426 (-1870 257);
PAINT SKYBLUE (-1870 257);
DISPLAY INVISIBLE (-1870 257);
FORCEPROP 1 LAST PATH I242
J 0
(-1775 325);
DISPLAY 0.872340 (-1775 325);
PAINT AQUA (-1775 325);
DISPLAY INVISIBLE (-1775 325);
FORCEPROP 1 LAST BODY_TYPE PLUMBING
J 0
(-1870 257);
DISPLAY 0.340426 (-1870 257);
PAINT GREEN (-1870 257);
DISPLAY INVISIBLE (-1870 257);
FORCEPROP 1 LAST HDL_POWER PVDDQ_ABC
J 1
(-1825 350);
DISPLAY 0.872340 (-1825 350);
PAINT GREEN (-1825 350);
DISPLAY INVISIBLE (-1825 350);
FORCEADD GND..1
(-1825 -300);
FORCEPROP 3 LASTPIN (-1825 -250) SIG_NAME GND\g
J 0
(-1815 -240);
DISPLAY 0.659574 (-1815 -240);
PAINT MONO (-1815 -240);
DISPLAY INVISIBLE (-1815 -240);
FORCEPROP 2 LAST BOM_COST PROC_VRD_VCCIN_CPU0
J 0
(-2200 -225);
DISPLAY 1.446809 (-2200 -225);
PAINT MONO (-2200 -225);
DISPLAY INVISIBLE (-2200 -225);
FORCEPROP 2 LAST ROOM VDDQ_ABC_PWR_VR
J 0
(-2375 -225);
DISPLAY 1.936170 (-2375 -225);
PAINT ORANGE (-2375 -225);
DISPLAY INVISIBLE (-2375 -225);
FORCEPROP 2 LAST CDS_LIB mstr_symbols
J 0
(-1825 -300);
PAINT ORANGE (-1825 -300);
DISPLAY INVISIBLE (-1825 -300);
FORCEPROP 1 LAST VOLTAGE 0
J 0
(-1825 -300);
PAINT SKYBLUE (-1825 -300);
DISPLAY INVISIBLE (-1825 -300);
FORCEPROP 1 LAST SIZE 1B
J 0
(-1750 -350);
DISPLAY 1.723404 (-1750 -350);
PAINT GREEN (-1750 -350);
DISPLAY INVISIBLE (-1750 -350);
FORCEPROP 1 LAST PATH I248
J 0
(-1750 -300);
DISPLAY 0.872340 (-1750 -300);
PAINT AQUA (-1750 -300);
DISPLAY INVISIBLE (-1750 -300);
FORCEPROP 1 LAST BODY_TYPE PLUMBING
J 0
(-1870 -343);
DISPLAY 0.340426 (-1870 -343);
PAINT GREEN (-1870 -343);
DISPLAY INVISIBLE (-1870 -343);
FORCEPROP 1 LAST HDL_POWER GND
J 0
(-1825 -150);
DISPLAY 1.723404 (-1825 -150);
PAINT GREEN (-1825 -150);
DISPLAY INVISIBLE (-1825 -150);
FORCEADD PVDDQ_ABC..1
(-1825 -400);
FORCEPROP 3 LASTPIN (-1825 -450) SIG_NAME PVDDQ_ABC\g
J 0
(-1815 -440);
DISPLAY 0.659574 (-1815 -440);
PAINT MONO (-1815 -440);
DISPLAY INVISIBLE (-1815 -440);
FORCEPROP 2 LAST ROOM VDDQ_ABC_PWR_VR
J 0
(-1825 -300);
DISPLAY 1.936170 (-1825 -300);
PAINT ORANGE (-1825 -300);
DISPLAY INVISIBLE (-1825 -300);
FORCEPROP 2 LAST BOM_COST PROC_SOCKET 
J 0
(-1825 -300);
DISPLAY 1.446809 (-1825 -300);
PAINT MONO (-1825 -300);
DISPLAY INVISIBLE (-1825 -300);
FORCEPROP 1 LAST PATH I249
J 0
(-1775 -375);
DISPLAY 0.872340 (-1775 -375);
PAINT AQUA (-1775 -375);
DISPLAY INVISIBLE (-1775 -375);
FORCEPROP 2 LAST CDS_LIB mstr_symbols
J 0
(-1825 -400);
PAINT ORANGE (-1825 -400);
DISPLAY INVISIBLE (-1825 -400);
FORCEPROP 1 LAST VOLTAGE 1.2V
J 0
(-1870 -443);
DISPLAY 0.340426 (-1870 -443);
PAINT SKYBLUE (-1870 -443);
DISPLAY INVISIBLE (-1870 -443);
FORCEPROP 1 LAST BODY_TYPE PLUMBING
J 0
(-1870 -443);
DISPLAY 0.340426 (-1870 -443);
PAINT GREEN (-1870 -443);
DISPLAY INVISIBLE (-1870 -443);
FORCEPROP 1 LAST HDL_POWER PVDDQ_ABC
J 1
(-1825 -350);
DISPLAY 0.872340 (-1825 -350);
PAINT GREEN (-1825 -350);
DISPLAY INVISIBLE (-1825 -350);
FORCEADD GND..1
(-1825 -1050);
FORCEPROP 3 LASTPIN (-1825 -1000) SIG_NAME GND\g
J 0
(-1815 -990);
DISPLAY 0.659574 (-1815 -990);
PAINT MONO (-1815 -990);
DISPLAY INVISIBLE (-1815 -990);
FORCEPROP 2 LAST BOM_COST PROC_VRD_VCCIN_CPU0
J 0
(-2200 -975);
DISPLAY 1.446809 (-2200 -975);
PAINT MONO (-2200 -975);
DISPLAY INVISIBLE (-2200 -975);
FORCEPROP 2 LAST ROOM VDDQ_ABC_PWR_VR
J 0
(-2375 -975);
DISPLAY 1.936170 (-2375 -975);
PAINT ORANGE (-2375 -975);
DISPLAY INVISIBLE (-2375 -975);
FORCEPROP 2 LAST CDS_LIB mstr_symbols
J 0
(-1825 -1050);
PAINT ORANGE (-1825 -1050);
DISPLAY INVISIBLE (-1825 -1050);
FORCEPROP 1 LAST VOLTAGE 0
J 0
(-1825 -1050);
PAINT SKYBLUE (-1825 -1050);
DISPLAY INVISIBLE (-1825 -1050);
FORCEPROP 1 LAST PATH I251
J 0
(-1750 -1050);
DISPLAY 0.872340 (-1750 -1050);
PAINT AQUA (-1750 -1050);
DISPLAY INVISIBLE (-1750 -1050);
FORCEPROP 1 LAST SIZE 1B
J 0
(-1750 -1100);
DISPLAY 1.723404 (-1750 -1100);
PAINT GREEN (-1750 -1100);
DISPLAY INVISIBLE (-1750 -1100);
FORCEPROP 1 LAST BODY_TYPE PLUMBING
J 0
(-1870 -1093);
DISPLAY 0.340426 (-1870 -1093);
PAINT GREEN (-1870 -1093);
DISPLAY INVISIBLE (-1870 -1093);
FORCEPROP 1 LAST HDL_POWER GND
J 0
(-1825 -900);
DISPLAY 1.723404 (-1825 -900);
PAINT GREEN (-1825 -900);
DISPLAY INVISIBLE (-1825 -900);
FORCEADD SHUNT..1
(125 1500);
FORCEPROP 1 LAST LOCATION SH4U1
J 0
(50 1550);
DISPLAY 0.617021 (50 1550);
PAINT AQUA (50 1550);
FORCEPROP 1 LASTPIN (275 1500) $PN 2
J 0
(235 1510);
DISPLAY 0.617021 (235 1510);
PAINT ORANGE (235 1510);
FORCEPROP 1 LASTPIN (-25 1500) $PN 1
J 2
(25 1510);
DISPLAY 0.617021 (25 1510);
PAINT ORANGE (25 1510);
FORCEPROP 1 LAST PART_NUMBER N_A
J 0
(50 1410);
DISPLAY 0.617021 (50 1410);
PAINT BLUE (50 1410);
FORCEPROP 1 LAST PIN_SHORT A:B
J 0
(50 1250);
DISPLAY 1.021277 (50 1250);
PAINT ORANGE (50 1250);
DISPLAY INVISIBLE (50 1250);
FORCEPROP 1 LAST PACK_TYPE SH0201
J 0
(65 1315);
DISPLAY 0.978723 (65 1315);
PAINT SKYBLUE (65 1315);
DISPLAY INVISIBLE (65 1315);
FORCEPROP 1 LAST MATERIAL EMPTY
J 0
(50 1365);
DISPLAY 0.978723 (50 1365);
PAINT RED (50 1365);
DISPLAY INVISIBLE (50 1365);
FORCEPROP 2 LAST CDS_LIB mstr_misc
J 0
(125 1500);
PAINT ORANGE (125 1500);
DISPLAY INVISIBLE (125 1500);
FORCEPROP 1 LAST PATH I259
J 0
(75 1600);
DISPLAY 0.978723 (75 1600);
PAINT ORANGE (75 1600);
DISPLAY INVISIBLE (75 1600);
FORCEPROP 0 LAST SEC 1
J 0
(50 1600);
DISPLAY 0.680851 (50 1600);
PAINT MONO (50 1600);
DISPLAY INVISIBLE (50 1600);
FORCEPROP 2 LAST SEC_TYPE SH0201
J 0
(75 1650);
DISPLAY 1.021277 (75 1650);
PAINT ORANGE (75 1650);
DISPLAY INVISIBLE (75 1650);
FORCEADD SHUNT..1
(150 1950);
FORCEPROP 1 LAST LOCATION SH4U2
J 0
(75 2000);
DISPLAY 0.617021 (75 2000);
PAINT AQUA (75 2000);
FORCEPROP 1 LAST PART_NUMBER N_A
J 0
(75 1860);
DISPLAY 0.617021 (75 1860);
PAINT BLUE (75 1860);
FORCEPROP 1 LASTPIN (300 1950) $PN 2
J 0
(260 1960);
DISPLAY 0.617021 (260 1960);
PAINT ORANGE (260 1960);
FORCEPROP 1 LASTPIN (0 1950) $PN 1
J 2
(50 1960);
DISPLAY 0.617021 (50 1960);
PAINT ORANGE (50 1960);
FORCEPROP 1 LAST PIN_SHORT A:B
J 0
(75 1700);
DISPLAY 1.021277 (75 1700);
PAINT ORANGE (75 1700);
DISPLAY INVISIBLE (75 1700);
FORCEPROP 1 LAST PACK_TYPE SH0201
J 0
(90 1765);
DISPLAY 0.978723 (90 1765);
PAINT SKYBLUE (90 1765);
DISPLAY INVISIBLE (90 1765);
FORCEPROP 1 LAST MATERIAL EMPTY
J 0
(75 1815);
DISPLAY 0.978723 (75 1815);
PAINT RED (75 1815);
DISPLAY INVISIBLE (75 1815);
FORCEPROP 2 LAST CDS_LIB mstr_misc
J 0
(150 1950);
PAINT ORANGE (150 1950);
DISPLAY INVISIBLE (150 1950);
FORCEPROP 0 LAST SEC 1
J 0
(75 2050);
DISPLAY 0.680851 (75 2050);
PAINT MONO (75 2050);
DISPLAY INVISIBLE (75 2050);
FORCEPROP 1 LAST PATH I260
J 0
(100 2050);
DISPLAY 0.978723 (100 2050);
PAINT ORANGE (100 2050);
DISPLAY INVISIBLE (100 2050);
FORCEPROP 2 LAST SEC_TYPE SH0201
J 0
(100 2100);
DISPLAY 1.021277 (100 2100);
PAINT ORANGE (100 2100);
DISPLAY INVISIBLE (100 2100);
FORCEADD IND-100NH-35-GP..1
R 1
(-200 925);
FORCEPROP 2 LAST TYPE IRMS=29A@DELTA_T<45C
J 0
(-350 700);
DISPLAY 0.638298 (-350 700);
PAINT GREEN (-350 700);
FORCEPROP 2 LAST PACK_SIZE DCR=0.16MOHM
J 0
(-350 650);
DISPLAY 0.638298 (-350 650);
PAINT GREEN (-350 650);
FORCEPROP 2 LAST RATED ISAT=16A@25C
J 0
(-350 750);
DISPLAY 0.638298 (-350 750);
PAINT GREEN (-350 750);
FORCEPROP 2 LAST ATTRIBUTE 100NH
J 0
(-350 800);
DISPLAY 0.638298 (-350 800);
PAINT GREEN (-350 800);
FORCEPROP 1 LAST VALUE IND-100NH-35-GP
J 0
(-350 850);
DISPLAY 0.617021 (-350 850);
PAINT GREEN (-350 850);
FORCEPROP 1 LAST LOCATION L7F2
J 0
(-325 975);
DISPLAY 0.617021 (-325 975);
PAINT GREEN (-325 975);
FORCEPROP 2 LASTPIN (-50 900) $PN 2
J 0
(-40 910);
DISPLAY 0.808511 (-40 910);
PAINT ORANGE (-40 910);
FORCEPROP 2 LASTPIN (-350 900) $PN 1
J 2
(-360 910);
DISPLAY 0.808511 (-360 910);
PAINT ORANGE (-360 910);
FORCEPROP 1 LAST PACK_TYPE DISCRET-G8
R 1
J 0
(-200 925);
DISPLAY 0.617021 (-200 925);
PAINT GREEN (-200 925);
DISPLAY INVISIBLE (-200 925);
FORCEPROP 2 LAST SEC 1
J 0
(-350 900);
DISPLAY 0.680851 (-350 900);
PAINT MONO (-350 900);
DISPLAY INVISIBLE (-350 900);
FORCEPROP 2 LAST SEC_TYPE DISCRET-G8
J 0
(-350 900);
DISPLAY 1.021277 (-350 900);
PAINT ORANGE (-350 900);
DISPLAY INVISIBLE (-350 900);
FORCEPROP 1 LAST PART_NUMBER 068.1011N.M001
R 1
J 0
(-200 925);
DISPLAY 0.617021 (-200 925);
PAINT GREEN (-200 925);
DISPLAY INVISIBLE (-200 925);
FORCEPROP 2 LAST CDS_LIB w_hdl
R 1
J 0
(-200 925);
PAINT MONO (-200 925);
DISPLAY INVISIBLE (-200 925);
FORCEPROP 1 LAST CDS_LMAN_SYM_OUTLINE -75,100,75,-100
R 1
J 0
(-200 925);
DISPLAY 0.468085 (-200 925);
PAINT GREEN (-200 925);
DISPLAY INVISIBLE (-200 925);
FORCEPROP 1 LAST PATH I261
R 1
J 0
(-200 925);
DISPLAY 0.617021 (-200 925);
PAINT GREEN (-200 925);
DISPLAY INVISIBLE (-200 925);
FORCEADD PVDDQ_ABC..1
(1025 3125);
FORCEPROP 3 LASTPIN (1025 3075) SIG_NAME PVDDQ_ABC\g
J 0
(1035 3085);
DISPLAY 0.659574 (1035 3085);
PAINT MONO (1035 3085);
DISPLAY INVISIBLE (1035 3085);
FORCEPROP 2 LAST CDS_LIB mstr_symbols
J 0
(1025 3125);
PAINT ORANGE (1025 3125);
DISPLAY INVISIBLE (1025 3125);
FORCEPROP 1 LAST PATH I264
J 0
(1075 3150);
DISPLAY 0.872340 (1075 3150);
PAINT AQUA (1075 3150);
DISPLAY INVISIBLE (1075 3150);
FORCEPROP 1 LAST VOLTAGE 1.2V
J 0
(980 3082);
DISPLAY 0.340426 (980 3082);
PAINT SKYBLUE (980 3082);
DISPLAY INVISIBLE (980 3082);
FORCEPROP 2 LAST BOM_COST MEM_VRD_PVDDQ_CD
J 0
(1100 3225);
PAINT MONO (1100 3225);
DISPLAY INVISIBLE (1100 3225);
FORCEPROP 2 LAST ROOM VDDQ_ABC_PWR_VR
J 0
(1275 3225);
PAINT ORANGE (1275 3225);
DISPLAY INVISIBLE (1275 3225);
FORCEPROP 1 LAST BODY_TYPE PLUMBING
J 0
(980 3082);
DISPLAY 0.340426 (980 3082);
PAINT GREEN (980 3082);
DISPLAY INVISIBLE (980 3082);
FORCEPROP 1 LAST HDL_POWER PVDDQ_ABC
J 1
(1025 3175);
DISPLAY 0.872340 (1025 3175);
PAINT GREEN (1025 3175);
DISPLAY INVISIBLE (1025 3175);
FORCEADD GND..1
(1025 2525);
FORCEPROP 3 LASTPIN (1025 2575) SIG_NAME GND\g
J 0
(1035 2585);
DISPLAY 0.659574 (1035 2585);
PAINT MONO (1035 2585);
DISPLAY INVISIBLE (1035 2585);
FORCEPROP 1 LAST VOLTAGE 0
J 0
(1025 2525);
PAINT SKYBLUE (1025 2525);
DISPLAY INVISIBLE (1025 2525);
FORCEPROP 1 LAST SIZE 1B
J 0
(1100 2475);
DISPLAY 0.893617 (1100 2475);
PAINT GREEN (1100 2475);
DISPLAY INVISIBLE (1100 2475);
FORCEPROP 2 LAST CDS_LIB mstr_symbols
J 0
(1025 2525);
PAINT ORANGE (1025 2525);
DISPLAY INVISIBLE (1025 2525);
FORCEPROP 1 LAST PATH I267
J 0
(1100 2525);
DISPLAY 0.872340 (1100 2525);
PAINT AQUA (1100 2525);
DISPLAY INVISIBLE (1100 2525);
FORCEPROP 1 LAST BODY_TYPE PLUMBING
J 0
(980 2482);
DISPLAY 0.340426 (980 2482);
PAINT GREEN (980 2482);
DISPLAY INVISIBLE (980 2482);
FORCEPROP 1 LAST HDL_POWER GND
J 0
(1025 2675);
DISPLAY 0.893617 (1025 2675);
PAINT GREEN (1025 2675);
DISPLAY INVISIBLE (1025 2675);
FORCEADD CAP_A..1
(1000 1950);
FORCEPROP 1 LASTPIN (1000 2050) $PN 1
J 0
(1010 2030);
DISPLAY 0.617021 (1010 2030);
PAINT GREEN (1010 2030);
FORCEPROP 1 LASTPIN (1000 1850) $PN 2
J 0
(1010 1830);
DISPLAY 0.617021 (1010 1830);
PAINT GREEN (1010 1830);
FORCEPROP 1 LAST LOCATION C5D58
J 0
(1050 2050);
DISPLAY 0.617021 (1050 2050);
PAINT AQUA (1050 2050);
FORCEPROP 1 LAST VALUE 22.0UF
J 0
(1050 2000);
DISPLAY 0.617021 (1050 2000);
PAINT SKYBLUE (1050 2000);
FORCEPROP 1 LAST VOLTAGE 4V
J 0
(1050 1950);
DISPLAY 0.617021 (1050 1950);
PAINT SKYBLUE (1050 1950);
FORCEPROP 1 LAST TOLERANCE 20%
J 0
(1050 1900);
DISPLAY 0.617021 (1050 1900);
PAINT SKYBLUE (1050 1900);
FORCEPROP 1 LAST MATERIAL X6S
J 0
(1050 1850);
DISPLAY 0.617021 (1050 1850);
PAINT SKYBLUE (1050 1850);
FORCEPROP 1 LAST PART_NUMBER E15431-004
J 0
(1050 1800);
DISPLAY 0.617021 (1050 1800);
PAINT BLUE (1050 1800);
FORCEPROP 0 LAST GROUP PWR_MLCC_CAP
J 0
(1056 1712);
DISPLAY 0.638298 (1056 1712);
PAINT BROWN (1056 1712);
DISPLAY BOTH (1056 1712);
FORCEPROP 1 LAST PACK_TYPE 0603V
J 0
(1050 1750);
DISPLAY 0.617021 (1050 1750);
PAINT SKYBLUE (1050 1750);
FORCEPROP 1 LAST PATH I269
J 0
(1050 2100);
DISPLAY 0.978723 (1050 2100);
PAINT WHITE (1050 2100);
DISPLAY INVISIBLE (1050 2100);
FORCEPROP 2 LAST CDS_LOCATION C5D58
J 0
(1050 2050);
DISPLAY 0.617021 (1050 2050);
PAINT AQUA (1050 2050);
DISPLAY INVISIBLE (1050 2050);
FORCEPROP 2 LAST BOM_COST PROC_SOCKET
J 0
(1050 2150);
DISPLAY 1.021277 (1050 2150);
PAINT ORANGE (1050 2150);
DISPLAY INVISIBLE (1050 2150);
FORCEPROP 2 LAST CDS_LIB dev_discrete
J 0
(1000 1950);
PAINT ORANGE (1000 1950);
DISPLAY INVISIBLE (1000 1950);
FORCEPROP 2 LAST CDS_SEC 1
J 0
(1050 2150);
PAINT MONO (1050 2150);
DISPLAY INVISIBLE (1050 2150);
FORCEPROP 2 LAST $SEC 1
J 0
(1050 2150);
PAINT MONO (1050 2150);
DISPLAY INVISIBLE (1050 2150);
FORCEPROP 2 LAST ROOM PVCCIN_CPU0_DECAP_VR
J 0
(1050 2100);
DISPLAY 1.021277 (1050 2100);
PAINT ORANGE (1050 2100);
DISPLAY INVISIBLE (1050 2100);
FORCEADD CAP_A..1
(1900 1950);
FORCEPROP 1 LAST TOLERANCE 20%
J 0
(1950 1900);
DISPLAY 0.617021 (1950 1900);
PAINT SKYBLUE (1950 1900);
FORCEPROP 1 LAST VALUE 22.0UF
J 0
(1950 2000);
DISPLAY 0.617021 (1950 2000);
PAINT SKYBLUE (1950 2000);
FORCEPROP 1 LAST LOCATION C5D61
J 0
(1950 2050);
DISPLAY 0.617021 (1950 2050);
PAINT AQUA (1950 2050);
FORCEPROP 0 LAST GROUP PWR_MLCC_CAP
J 0
(1956 1662);
DISPLAY 0.638298 (1956 1662);
PAINT BROWN (1956 1662);
DISPLAY BOTH (1956 1662);
FORCEPROP 1 LAST PART_NUMBER E15431-004
J 0
(1950 1800);
DISPLAY 0.617021 (1950 1800);
PAINT BLUE (1950 1800);
FORCEPROP 1 LAST PACK_TYPE 0603V
J 0
(1950 1750);
DISPLAY 0.617021 (1950 1750);
PAINT SKYBLUE (1950 1750);
FORCEPROP 1 LAST VOLTAGE 4V
J 0
(1950 1950);
DISPLAY 0.617021 (1950 1950);
PAINT SKYBLUE (1950 1950);
FORCEPROP 1 LAST MATERIAL X6S
J 0
(1950 1850);
DISPLAY 0.617021 (1950 1850);
PAINT SKYBLUE (1950 1850);
FORCEPROP 1 LASTPIN (1900 1850) $PN 2
J 0
(1910 1830);
DISPLAY 0.617021 (1910 1830);
PAINT GREEN (1910 1830);
FORCEPROP 1 LASTPIN (1900 2050) $PN 1
J 0
(1910 2030);
DISPLAY 0.617021 (1910 2030);
PAINT GREEN (1910 2030);
FORCEPROP 1 LAST PATH I270
J 0
(1950 2100);
DISPLAY 0.978723 (1950 2100);
PAINT WHITE (1950 2100);
DISPLAY INVISIBLE (1950 2100);
FORCEPROP 2 LAST CDS_LOCATION C5D61
J 0
(1950 2050);
DISPLAY 0.617021 (1950 2050);
PAINT AQUA (1950 2050);
DISPLAY INVISIBLE (1950 2050);
FORCEPROP 2 LAST BOM_COST PROC_SOCKET
J 0
(1950 2150);
DISPLAY 1.021277 (1950 2150);
PAINT ORANGE (1950 2150);
DISPLAY INVISIBLE (1950 2150);
FORCEPROP 2 LAST CDS_LIB dev_discrete
J 0
(1900 1950);
PAINT ORANGE (1900 1950);
DISPLAY INVISIBLE (1900 1950);
FORCEPROP 2 LAST CDS_SEC 1
J 0
(1950 2150);
PAINT MONO (1950 2150);
DISPLAY INVISIBLE (1950 2150);
FORCEPROP 2 LAST $SEC 1
J 0
(1950 2150);
PAINT MONO (1950 2150);
DISPLAY INVISIBLE (1950 2150);
FORCEPROP 2 LAST ROOM PVCCIN_CPU0_DECAP_VR
J 0
(1950 2100);
DISPLAY 1.021277 (1950 2100);
PAINT ORANGE (1950 2100);
DISPLAY INVISIBLE (1950 2100);
FORCEADD CAP_A..1
(1300 1950);
FORCEPROP 1 LASTPIN (1300 2050) $PN 1
J 0
(1310 2030);
DISPLAY 0.617021 (1310 2030);
PAINT GREEN (1310 2030);
FORCEPROP 1 LAST TOLERANCE 20%
J 0
(1350 1900);
DISPLAY 0.617021 (1350 1900);
PAINT SKYBLUE (1350 1900);
FORCEPROP 1 LAST MATERIAL X6S
J 0
(1350 1850);
DISPLAY 0.617021 (1350 1850);
PAINT SKYBLUE (1350 1850);
FORCEPROP 1 LAST PART_NUMBER E15431-004
J 0
(1350 1800);
DISPLAY 0.617021 (1350 1800);
PAINT BLUE (1350 1800);
FORCEPROP 1 LASTPIN (1300 1850) $PN 2
J 0
(1310 1830);
DISPLAY 0.617021 (1310 1830);
PAINT GREEN (1310 1830);
FORCEPROP 1 LAST PACK_TYPE 0603V
J 0
(1350 1750);
DISPLAY 0.617021 (1350 1750);
PAINT SKYBLUE (1350 1750);
FORCEPROP 1 LAST LOCATION C5D59
J 0
(1350 2050);
DISPLAY 0.617021 (1350 2050);
PAINT AQUA (1350 2050);
FORCEPROP 1 LAST VALUE 22.0UF
J 0
(1350 2000);
DISPLAY 0.617021 (1350 2000);
PAINT SKYBLUE (1350 2000);
FORCEPROP 1 LAST VOLTAGE 4V
J 0
(1350 1950);
DISPLAY 0.617021 (1350 1950);
PAINT SKYBLUE (1350 1950);
FORCEPROP 0 LAST GROUP PWR_MLCC_CAP
J 0
(1331 1662);
DISPLAY 0.638298 (1331 1662);
PAINT BROWN (1331 1662);
DISPLAY BOTH (1331 1662);
FORCEPROP 1 LAST PATH I271
J 0
(1350 2100);
DISPLAY 0.978723 (1350 2100);
PAINT WHITE (1350 2100);
DISPLAY INVISIBLE (1350 2100);
FORCEPROP 2 LAST ROOM PVCCIN_CPU0_DECAP_VR
J 0
(1350 2100);
DISPLAY 1.021277 (1350 2100);
PAINT ORANGE (1350 2100);
DISPLAY INVISIBLE (1350 2100);
FORCEPROP 2 LAST $SEC 1
J 0
(1350 2150);
PAINT MONO (1350 2150);
DISPLAY INVISIBLE (1350 2150);
FORCEPROP 2 LAST CDS_SEC 1
J 0
(1350 2150);
PAINT MONO (1350 2150);
DISPLAY INVISIBLE (1350 2150);
FORCEPROP 2 LAST CDS_LIB dev_discrete
J 0
(1300 1950);
PAINT ORANGE (1300 1950);
DISPLAY INVISIBLE (1300 1950);
FORCEPROP 2 LAST BOM_COST PROC_SOCKET
J 0
(1350 2150);
DISPLAY 1.021277 (1350 2150);
PAINT ORANGE (1350 2150);
DISPLAY INVISIBLE (1350 2150);
FORCEPROP 2 LAST CDS_LOCATION C5D59
J 0
(1350 2050);
DISPLAY 0.617021 (1350 2050);
PAINT AQUA (1350 2050);
DISPLAY INVISIBLE (1350 2050);
FORCEADD CAP_A..1
(1600 1950);
FORCEPROP 0 LAST GROUP PWR_MLCC_CAP
J 0
(1656 1712);
DISPLAY 0.638298 (1656 1712);
PAINT BROWN (1656 1712);
DISPLAY BOTH (1656 1712);
FORCEPROP 1 LASTPIN (1600 1850) $PN 2
J 0
(1610 1830);
DISPLAY 0.617021 (1610 1830);
PAINT GREEN (1610 1830);
FORCEPROP 1 LAST MATERIAL X6S
J 0
(1650 1850);
DISPLAY 0.617021 (1650 1850);
PAINT SKYBLUE (1650 1850);
FORCEPROP 1 LAST VOLTAGE 4V
J 0
(1650 1950);
DISPLAY 0.617021 (1650 1950);
PAINT SKYBLUE (1650 1950);
FORCEPROP 1 LAST PART_NUMBER E15431-004
J 0
(1650 1800);
DISPLAY 0.617021 (1650 1800);
PAINT BLUE (1650 1800);
FORCEPROP 1 LAST PACK_TYPE 0603V
J 0
(1650 1750);
DISPLAY 0.617021 (1650 1750);
PAINT SKYBLUE (1650 1750);
FORCEPROP 1 LASTPIN (1600 2050) $PN 1
J 0
(1610 2030);
DISPLAY 0.617021 (1610 2030);
PAINT GREEN (1610 2030);
FORCEPROP 1 LAST TOLERANCE 20%
J 0
(1650 1900);
DISPLAY 0.617021 (1650 1900);
PAINT SKYBLUE (1650 1900);
FORCEPROP 1 LAST LOCATION C5D60
J 0
(1650 2050);
DISPLAY 0.617021 (1650 2050);
PAINT AQUA (1650 2050);
FORCEPROP 1 LAST VALUE 22.0UF
J 0
(1650 2000);
DISPLAY 0.617021 (1650 2000);
PAINT SKYBLUE (1650 2000);
FORCEPROP 1 LAST PATH I272
J 0
(1650 2100);
DISPLAY 0.978723 (1650 2100);
PAINT WHITE (1650 2100);
DISPLAY INVISIBLE (1650 2100);
FORCEPROP 2 LAST ROOM PVCCIN_CPU0_DECAP_VR
J 0
(1650 2100);
DISPLAY 1.021277 (1650 2100);
PAINT ORANGE (1650 2100);
DISPLAY INVISIBLE (1650 2100);
FORCEPROP 2 LAST $SEC 1
J 0
(1650 2150);
PAINT MONO (1650 2150);
DISPLAY INVISIBLE (1650 2150);
FORCEPROP 2 LAST CDS_SEC 1
J 0
(1650 2150);
PAINT MONO (1650 2150);
DISPLAY INVISIBLE (1650 2150);
FORCEPROP 2 LAST CDS_LIB dev_discrete
J 0
(1600 1950);
PAINT ORANGE (1600 1950);
DISPLAY INVISIBLE (1600 1950);
FORCEPROP 2 LAST BOM_COST PROC_SOCKET
J 0
(1650 2150);
DISPLAY 1.021277 (1650 2150);
PAINT ORANGE (1650 2150);
DISPLAY INVISIBLE (1650 2150);
FORCEPROP 2 LAST CDS_LOCATION C5D60
J 0
(1650 2050);
DISPLAY 0.617021 (1650 2050);
PAINT AQUA (1650 2050);
DISPLAY INVISIBLE (1650 2050);
FORCEADD PVDDQ_ABC..1
(1000 2200);
FORCEPROP 3 LASTPIN (1000 2150) SIG_NAME PVDDQ_ABC\g
J 0
(1010 2160);
DISPLAY 0.659574 (1010 2160);
PAINT MONO (1010 2160);
DISPLAY INVISIBLE (1010 2160);
FORCEPROP 1 LAST PATH I273
J 0
(1050 2225);
DISPLAY 0.872340 (1050 2225);
PAINT AQUA (1050 2225);
DISPLAY INVISIBLE (1050 2225);
FORCEPROP 1 LAST VOLTAGE 1.2V
J 0
(955 2157);
DISPLAY 0.340426 (955 2157);
PAINT SKYBLUE (955 2157);
DISPLAY INVISIBLE (955 2157);
FORCEPROP 2 LAST CDS_LIB mstr_symbols
J 0
(1000 2200);
PAINT ORANGE (1000 2200);
DISPLAY INVISIBLE (1000 2200);
FORCEPROP 2 LAST BOM_COST MEM_VRD_PVDDQ_CD
J 0
(1075 2300);
PAINT MONO (1075 2300);
DISPLAY INVISIBLE (1075 2300);
FORCEPROP 2 LAST ROOM VDDQ_ABC_PWR_VR
J 0
(1250 2300);
PAINT ORANGE (1250 2300);
DISPLAY INVISIBLE (1250 2300);
FORCEPROP 1 LAST BODY_TYPE PLUMBING
J 0
(955 2157);
DISPLAY 0.340426 (955 2157);
PAINT GREEN (955 2157);
DISPLAY INVISIBLE (955 2157);
FORCEPROP 1 LAST HDL_POWER PVDDQ_ABC
J 1
(1000 2250);
DISPLAY 0.872340 (1000 2250);
PAINT GREEN (1000 2250);
DISPLAY INVISIBLE (1000 2250);
FORCEADD GND..1
(1900 1600);
FORCEPROP 3 LASTPIN (1900 1650) SIG_NAME GND\g
J 0
(1910 1660);
DISPLAY 0.659574 (1910 1660);
PAINT MONO (1910 1660);
DISPLAY INVISIBLE (1910 1660);
FORCEPROP 1 LAST PATH I274
J 0
(1975 1600);
DISPLAY 0.872340 (1975 1600);
PAINT AQUA (1975 1600);
DISPLAY INVISIBLE (1975 1600);
FORCEPROP 2 LAST CDS_LIB mstr_symbols
J 0
(1900 1600);
PAINT ORANGE (1900 1600);
DISPLAY INVISIBLE (1900 1600);
FORCEPROP 1 LAST SIZE 1B
J 0
(1975 1550);
DISPLAY 0.893617 (1975 1550);
PAINT GREEN (1975 1550);
DISPLAY INVISIBLE (1975 1550);
FORCEPROP 1 LAST VOLTAGE 0
J 0
(1900 1600);
PAINT SKYBLUE (1900 1600);
DISPLAY INVISIBLE (1900 1600);
FORCEPROP 1 LAST BODY_TYPE PLUMBING
J 0
(1855 1557);
DISPLAY 0.340426 (1855 1557);
PAINT GREEN (1855 1557);
DISPLAY INVISIBLE (1855 1557);
FORCEPROP 1 LAST HDL_POWER GND
J 0
(1900 1750);
DISPLAY 0.893617 (1900 1750);
PAINT GREEN (1900 1750);
DISPLAY INVISIBLE (1900 1750);
FORCEADD GND..1
(2000 2600);
FORCEPROP 3 LASTPIN (2000 2650) SIG_NAME GND\g
J 0
(2010 2660);
DISPLAY 0.659574 (2010 2660);
PAINT MONO (2010 2660);
DISPLAY INVISIBLE (2010 2660);
FORCEPROP 1 LAST PATH I277
J 0
(2075 2600);
DISPLAY 0.872340 (2075 2600);
PAINT AQUA (2075 2600);
DISPLAY INVISIBLE (2075 2600);
FORCEPROP 2 LAST CDS_LIB mstr_symbols
J 0
(2000 2600);
PAINT ORANGE (2000 2600);
DISPLAY INVISIBLE (2000 2600);
FORCEPROP 1 LAST SIZE 1B
J 0
(2075 2550);
DISPLAY 0.893617 (2075 2550);
PAINT GREEN (2075 2550);
DISPLAY INVISIBLE (2075 2550);
FORCEPROP 1 LAST VOLTAGE 0
J 0
(2000 2600);
PAINT SKYBLUE (2000 2600);
DISPLAY INVISIBLE (2000 2600);
FORCEPROP 1 LAST BODY_TYPE PLUMBING
J 0
(1955 2557);
DISPLAY 0.340426 (1955 2557);
PAINT GREEN (1955 2557);
DISPLAY INVISIBLE (1955 2557);
FORCEPROP 1 LAST HDL_POWER GND
J 0
(2000 2750);
DISPLAY 0.893617 (2000 2750);
PAINT GREEN (2000 2750);
DISPLAY INVISIBLE (2000 2750);
FORCEADD PVDDQ_ABC..1
(2000 3150);
FORCEPROP 3 LASTPIN (2000 3100) SIG_NAME PVDDQ_ABC\g
J 0
(2010 3110);
DISPLAY 0.659574 (2010 3110);
PAINT MONO (2010 3110);
DISPLAY INVISIBLE (2010 3110);
FORCEPROP 2 LAST CDS_LIB mstr_symbols
J 0
(2000 3150);
PAINT MONO (2000 3150);
DISPLAY INVISIBLE (2000 3150);
FORCEPROP 1 LAST PATH I278
J 0
(2050 3175);
DISPLAY 0.872340 (2050 3175);
PAINT AQUA (2050 3175);
DISPLAY INVISIBLE (2050 3175);
FORCEPROP 1 LAST VOLTAGE 1.2V
J 0
(1955 3107);
DISPLAY 0.340426 (1955 3107);
PAINT SKYBLUE (1955 3107);
DISPLAY INVISIBLE (1955 3107);
FORCEPROP 2 LAST BOM_COST MEM_VRD_PVDDQ_CD
J 0
(2075 3250);
PAINT MONO (2075 3250);
DISPLAY INVISIBLE (2075 3250);
FORCEPROP 2 LAST ROOM VDDQ_ABC_PWR_VR
J 0
(2250 3250);
PAINT ORANGE (2250 3250);
DISPLAY INVISIBLE (2250 3250);
FORCEPROP 1 LAST BODY_TYPE PLUMBING
J 0
(1955 3107);
DISPLAY 0.340426 (1955 3107);
PAINT GREEN (1955 3107);
DISPLAY INVISIBLE (1955 3107);
FORCEPROP 1 LAST HDL_POWER PVDDQ_ABC
J 1
(2000 3200);
DISPLAY 0.872340 (2000 3200);
PAINT GREEN (2000 3200);
DISPLAY INVISIBLE (2000 3200);
FORCEADD CAP_A..1
(-900 2850);
FORCEPROP 1 LAST VALUE 22.0UF
J 0
(-850 2900);
DISPLAY 0.617021 (-850 2900);
PAINT SKYBLUE (-850 2900);
FORCEPROP 1 LAST VOLTAGE 4V
J 0
(-850 2850);
DISPLAY 0.617021 (-850 2850);
PAINT SKYBLUE (-850 2850);
FORCEPROP 1 LAST TOLERANCE 20%
J 0
(-850 2800);
DISPLAY 0.617021 (-850 2800);
PAINT SKYBLUE (-850 2800);
FORCEPROP 1 LASTPIN (-900 2750) $PN 2
J 0
(-890 2730);
DISPLAY 0.617021 (-890 2730);
PAINT GREEN (-890 2730);
FORCEPROP 1 LAST PACK_TYPE 0603V
J 0
(-850 2650);
DISPLAY 0.617021 (-850 2650);
PAINT SKYBLUE (-850 2650);
FORCEPROP 1 LASTPIN (-900 2950) $PN 1
J 0
(-890 2930);
DISPLAY 0.617021 (-890 2930);
PAINT GREEN (-890 2930);
FORCEPROP 1 LAST LOCATION C5D54
J 0
(-850 2950);
DISPLAY 0.617021 (-850 2950);
PAINT AQUA (-850 2950);
FORCEPROP 1 LAST MATERIAL X6S
J 0
(-850 2750);
DISPLAY 0.617021 (-850 2750);
PAINT SKYBLUE (-850 2750);
FORCEPROP 1 LAST PART_NUMBER E15431-004
J 0
(-850 2700);
DISPLAY 0.617021 (-850 2700);
PAINT BLUE (-850 2700);
FORCEPROP 0 LAST GROUP PWR_MLCC_CAP
J 0
(-844 2612);
DISPLAY 0.638298 (-844 2612);
PAINT BROWN (-844 2612);
DISPLAY BOTH (-844 2612);
FORCEPROP 2 LAST CDS_LOCATION C5D54
J 0
(-850 2950);
DISPLAY 0.617021 (-850 2950);
PAINT AQUA (-850 2950);
DISPLAY INVISIBLE (-850 2950);
FORCEPROP 1 LAST PATH I279
J 0
(-850 3000);
DISPLAY 0.978723 (-850 3000);
PAINT WHITE (-850 3000);
DISPLAY INVISIBLE (-850 3000);
FORCEPROP 2 LAST BOM_COST PROC_SOCKET
J 0
(-850 3050);
DISPLAY 1.021277 (-850 3050);
PAINT ORANGE (-850 3050);
DISPLAY INVISIBLE (-850 3050);
FORCEPROP 2 LAST CDS_LIB dev_discrete
J 0
(-900 2850);
PAINT ORANGE (-900 2850);
DISPLAY INVISIBLE (-900 2850);
FORCEPROP 2 LAST CDS_SEC 1
J 0
(-850 3050);
PAINT MONO (-850 3050);
DISPLAY INVISIBLE (-850 3050);
FORCEPROP 2 LAST $SEC 1
J 0
(-850 3050);
PAINT MONO (-850 3050);
DISPLAY INVISIBLE (-850 3050);
FORCEPROP 2 LAST ROOM PVCCIN_CPU0_DECAP_VR
J 0
(-850 3000);
DISPLAY 1.021277 (-850 3000);
PAINT ORANGE (-850 3000);
DISPLAY INVISIBLE (-850 3000);
FORCEADD CAP_A..1
(-550 2850);
FORCEPROP 1 LAST TOLERANCE 20%
J 0
(-500 2800);
DISPLAY 0.617021 (-500 2800);
PAINT SKYBLUE (-500 2800);
FORCEPROP 1 LAST VOLTAGE 4V
J 0
(-500 2850);
DISPLAY 0.617021 (-500 2850);
PAINT SKYBLUE (-500 2850);
FORCEPROP 1 LASTPIN (-550 2950) $PN 1
J 0
(-540 2930);
DISPLAY 0.617021 (-540 2930);
PAINT GREEN (-540 2930);
FORCEPROP 1 LAST MATERIAL X6S
J 0
(-500 2750);
DISPLAY 0.617021 (-500 2750);
PAINT SKYBLUE (-500 2750);
FORCEPROP 1 LAST LOCATION C5D55
J 0
(-500 2950);
DISPLAY 0.617021 (-500 2950);
PAINT AQUA (-500 2950);
FORCEPROP 1 LAST VALUE 22.0UF
J 0
(-500 2900);
DISPLAY 0.617021 (-500 2900);
PAINT SKYBLUE (-500 2900);
FORCEPROP 0 LAST GROUP PWR_MLCC_CAP
J 0
(-494 2562);
DISPLAY 0.638298 (-494 2562);
PAINT BROWN (-494 2562);
DISPLAY BOTH (-494 2562);
FORCEPROP 1 LASTPIN (-550 2750) $PN 2
J 0
(-540 2730);
DISPLAY 0.617021 (-540 2730);
PAINT GREEN (-540 2730);
FORCEPROP 1 LAST PART_NUMBER E15431-004
J 0
(-500 2700);
DISPLAY 0.617021 (-500 2700);
PAINT BLUE (-500 2700);
FORCEPROP 1 LAST PACK_TYPE 0603V
J 0
(-500 2650);
DISPLAY 0.617021 (-500 2650);
PAINT SKYBLUE (-500 2650);
FORCEPROP 2 LAST CDS_LOCATION C5D55
J 0
(-500 2950);
DISPLAY 0.617021 (-500 2950);
PAINT AQUA (-500 2950);
DISPLAY INVISIBLE (-500 2950);
FORCEPROP 1 LAST PATH I280
J 0
(-500 3000);
DISPLAY 0.978723 (-500 3000);
PAINT WHITE (-500 3000);
DISPLAY INVISIBLE (-500 3000);
FORCEPROP 2 LAST ROOM PVCCIN_CPU0_DECAP_VR
J 0
(-500 3000);
DISPLAY 1.021277 (-500 3000);
PAINT ORANGE (-500 3000);
DISPLAY INVISIBLE (-500 3000);
FORCEPROP 2 LAST $SEC 1
J 0
(-500 3050);
PAINT MONO (-500 3050);
DISPLAY INVISIBLE (-500 3050);
FORCEPROP 2 LAST CDS_SEC 1
J 0
(-500 3050);
PAINT MONO (-500 3050);
DISPLAY INVISIBLE (-500 3050);
FORCEPROP 2 LAST CDS_LIB dev_discrete
J 0
(-550 2850);
PAINT ORANGE (-550 2850);
DISPLAY INVISIBLE (-550 2850);
FORCEPROP 2 LAST BOM_COST PROC_SOCKET
J 0
(-500 3050);
DISPLAY 1.021277 (-500 3050);
PAINT ORANGE (-500 3050);
DISPLAY INVISIBLE (-500 3050);
FORCEADD CAP_A..1
(-200 2850);
FORCEPROP 1 LAST TOLERANCE 20%
J 0
(-150 2800);
DISPLAY 0.617021 (-150 2800);
PAINT SKYBLUE (-150 2800);
FORCEPROP 1 LAST PART_NUMBER E15431-004
J 0
(-150 2700);
DISPLAY 0.617021 (-150 2700);
PAINT BLUE (-150 2700);
FORCEPROP 1 LAST LOCATION C5D56
J 0
(-150 2950);
DISPLAY 0.617021 (-150 2950);
PAINT AQUA (-150 2950);
FORCEPROP 1 LAST VOLTAGE 4V
J 0
(-150 2850);
DISPLAY 0.617021 (-150 2850);
PAINT SKYBLUE (-150 2850);
FORCEPROP 1 LAST VALUE 22.0UF
J 0
(-150 2900);
DISPLAY 0.617021 (-150 2900);
PAINT SKYBLUE (-150 2900);
FORCEPROP 1 LASTPIN (-200 2950) $PN 1
J 0
(-190 2930);
DISPLAY 0.617021 (-190 2930);
PAINT GREEN (-190 2930);
FORCEPROP 1 LASTPIN (-200 2750) $PN 2
J 0
(-190 2730);
DISPLAY 0.617021 (-190 2730);
PAINT GREEN (-190 2730);
FORCEPROP 1 LAST MATERIAL X6S
J 0
(-150 2750);
DISPLAY 0.617021 (-150 2750);
PAINT SKYBLUE (-150 2750);
FORCEPROP 0 LAST GROUP PWR_MLCC_CAP
J 0
(-144 2612);
DISPLAY 0.638298 (-144 2612);
PAINT BROWN (-144 2612);
DISPLAY BOTH (-144 2612);
FORCEPROP 1 LAST PACK_TYPE 0603V
J 0
(-150 2650);
DISPLAY 0.617021 (-150 2650);
PAINT SKYBLUE (-150 2650);
FORCEPROP 2 LAST CDS_LOCATION C5D56
J 0
(-150 2950);
DISPLAY 0.617021 (-150 2950);
PAINT AQUA (-150 2950);
DISPLAY INVISIBLE (-150 2950);
FORCEPROP 1 LAST PATH I281
J 0
(-150 3000);
DISPLAY 0.978723 (-150 3000);
PAINT WHITE (-150 3000);
DISPLAY INVISIBLE (-150 3000);
FORCEPROP 2 LAST ROOM PVCCIN_CPU0_DECAP_VR
J 0
(-150 3000);
DISPLAY 1.021277 (-150 3000);
PAINT ORANGE (-150 3000);
DISPLAY INVISIBLE (-150 3000);
FORCEPROP 2 LAST $SEC 1
J 0
(-150 3050);
PAINT MONO (-150 3050);
DISPLAY INVISIBLE (-150 3050);
FORCEPROP 2 LAST CDS_SEC 1
J 0
(-150 3050);
PAINT MONO (-150 3050);
DISPLAY INVISIBLE (-150 3050);
FORCEPROP 2 LAST CDS_LIB dev_discrete
J 0
(-200 2850);
PAINT ORANGE (-200 2850);
DISPLAY INVISIBLE (-200 2850);
FORCEPROP 2 LAST BOM_COST PROC_SOCKET
J 0
(-150 3050);
DISPLAY 1.021277 (-150 3050);
PAINT ORANGE (-150 3050);
DISPLAY INVISIBLE (-150 3050);
FORCEADD CAP_A..1
(150 2850);
FORCEPROP 1 LAST PART_NUMBER E15431-004
J 0
(200 2700);
DISPLAY 0.617021 (200 2700);
PAINT BLUE (200 2700);
FORCEPROP 1 LAST MATERIAL X6S
J 0
(200 2750);
DISPLAY 0.617021 (200 2750);
PAINT SKYBLUE (200 2750);
FORCEPROP 1 LASTPIN (150 2950) $PN 1
J 0
(160 2930);
DISPLAY 0.617021 (160 2930);
PAINT GREEN (160 2930);
FORCEPROP 1 LAST VALUE 22.0UF
J 0
(200 2900);
DISPLAY 0.617021 (200 2900);
PAINT SKYBLUE (200 2900);
FORCEPROP 1 LAST TOLERANCE 20%
J 0
(200 2800);
DISPLAY 0.617021 (200 2800);
PAINT SKYBLUE (200 2800);
FORCEPROP 1 LAST VOLTAGE 4V
J 0
(200 2850);
DISPLAY 0.617021 (200 2850);
PAINT SKYBLUE (200 2850);
FORCEPROP 1 LAST LOCATION C5D57
J 0
(200 2950);
DISPLAY 0.617021 (200 2950);
PAINT AQUA (200 2950);
FORCEPROP 1 LASTPIN (150 2750) $PN 2
J 0
(160 2730);
DISPLAY 0.617021 (160 2730);
PAINT GREEN (160 2730);
FORCEPROP 1 LAST PACK_TYPE 0603V
J 0
(200 2650);
DISPLAY 0.617021 (200 2650);
PAINT SKYBLUE (200 2650);
FORCEPROP 0 LAST GROUP PWR_MLCC_CAP
J 0
(206 2562);
DISPLAY 0.638298 (206 2562);
PAINT BROWN (206 2562);
DISPLAY BOTH (206 2562);
FORCEPROP 2 LAST CDS_LOCATION C5D57
J 0
(200 2950);
DISPLAY 0.617021 (200 2950);
PAINT AQUA (200 2950);
DISPLAY INVISIBLE (200 2950);
FORCEPROP 1 LAST PATH I282
J 0
(200 3000);
DISPLAY 0.978723 (200 3000);
PAINT WHITE (200 3000);
DISPLAY INVISIBLE (200 3000);
FORCEPROP 2 LAST BOM_COST PROC_SOCKET
J 0
(200 3050);
DISPLAY 1.021277 (200 3050);
PAINT ORANGE (200 3050);
DISPLAY INVISIBLE (200 3050);
FORCEPROP 2 LAST CDS_LIB dev_discrete
J 0
(150 2850);
PAINT ORANGE (150 2850);
DISPLAY INVISIBLE (150 2850);
FORCEPROP 2 LAST CDS_SEC 1
J 0
(200 3050);
PAINT MONO (200 3050);
DISPLAY INVISIBLE (200 3050);
FORCEPROP 2 LAST $SEC 1
J 0
(200 3050);
PAINT MONO (200 3050);
DISPLAY INVISIBLE (200 3050);
FORCEPROP 2 LAST ROOM PVCCIN_CPU0_DECAP_VR
J 0
(200 3000);
DISPLAY 1.021277 (200 3000);
PAINT ORANGE (200 3000);
DISPLAY INVISIBLE (200 3000);
FORCEADD CAP_A..1
(-1825 50);
FORCEPROP 0 LAST BOM_SS E15431-004
J 0
(-1775 -300);
DISPLAY 0.510638 (-1775 -300);
PAINT BROWN (-1775 -300);
DISPLAY BOTH (-1775 -300);
FORCEPROP 1 LAST VOLTAGE 4V
J 0
(-1775 50);
DISPLAY 0.617021 (-1775 50);
PAINT SKYBLUE (-1775 50);
FORCEPROP 1 LAST PACK_TYPE 0603V
J 0
(-1775 -150);
DISPLAY 0.617021 (-1775 -150);
PAINT SKYBLUE (-1775 -150);
FORCEPROP 1 LAST TOLERANCE 20%
J 0
(-1775 0);
DISPLAY 0.617021 (-1775 0);
PAINT SKYBLUE (-1775 0);
FORCEPROP 1 LAST MATERIAL X5R
J 0
(-1775 -50);
DISPLAY 0.617021 (-1775 -50);
PAINT SKYBLUE (-1775 -50);
FORCEPROP 1 LAST PART_NUMBER 602433-106
J 0
(-1775 -100);
DISPLAY 0.617021 (-1775 -100);
PAINT BLUE (-1775 -100);
FORCEPROP 1 LAST VALUE 47UF
J 0
(-1775 100);
DISPLAY 0.617021 (-1775 100);
PAINT SKYBLUE (-1775 100);
FORCEPROP 1 LAST LOCATION C5U2
J 0
(-1775 150);
DISPLAY 0.617021 (-1775 150);
PAINT AQUA (-1775 150);
FORCEPROP 0 LAST GROUP PWR_MLCC_CAP
J 0
(-1769 -188);
DISPLAY 0.638298 (-1769 -188);
PAINT BROWN (-1769 -188);
DISPLAY BOTH (-1769 -188);
FORCEPROP 1 LASTPIN (-1825 -50) $PN 2
J 0
(-1815 -70);
DISPLAY 0.617021 (-1815 -70);
PAINT ORANGE (-1815 -70);
FORCEPROP 1 LASTPIN (-1825 150) $PN 1
J 0
(-1815 130);
DISPLAY 0.617021 (-1815 130);
PAINT ORANGE (-1815 130);
FORCEPROP 1 LAST PATH I283
J 0
(-1775 200);
DISPLAY 0.978723 (-1775 200);
PAINT WHITE (-1775 200);
DISPLAY INVISIBLE (-1775 200);
FORCEPROP 2 LAST SEC_TYPE 0603V
J 0
(-1775 250);
DISPLAY 1.021277 (-1775 250);
PAINT ORANGE (-1775 250);
DISPLAY INVISIBLE (-1775 250);
FORCEPROP 2 LAST SEC 1
J 0
(-1775 250);
DISPLAY 0.680851 (-1775 250);
PAINT MONO (-1775 250);
DISPLAY INVISIBLE (-1775 250);
FORCEPROP 2 LAST CDS_SEC 1
J 0
(-1775 200);
PAINT ORANGE (-1775 200);
DISPLAY INVISIBLE (-1775 200);
FORCEPROP 2 LAST CDS_LIB dev_discrete
J 0
(-1825 50);
PAINT ORANGE (-1825 50);
DISPLAY INVISIBLE (-1825 50);
FORCEPROP 2 LAST CDS_LOCATION C5U2
J 0
(-1775 150);
DISPLAY 0.617021 (-1775 150);
PAINT AQUA (-1775 150);
DISPLAY INVISIBLE (-1775 150);
FORCEADD CAP_A..1
(-1525 50);
FORCEPROP 0 LAST BOM_SS E15431-004
J 0
(-1500 -350);
DISPLAY 0.510638 (-1500 -350);
PAINT BROWN (-1500 -350);
DISPLAY BOTH (-1500 -350);
FORCEPROP 0 LAST GROUP PWR_MLCC_CAP
J 0
(-1469 -238);
DISPLAY 0.638298 (-1469 -238);
PAINT BROWN (-1469 -238);
DISPLAY BOTH (-1469 -238);
FORCEPROP 1 LAST LOCATION C5U3
J 0
(-1475 150);
DISPLAY 0.617021 (-1475 150);
PAINT AQUA (-1475 150);
FORCEPROP 1 LAST MATERIAL X5R
J 0
(-1475 -50);
DISPLAY 0.617021 (-1475 -50);
PAINT SKYBLUE (-1475 -50);
FORCEPROP 1 LAST PART_NUMBER 602433-106
J 0
(-1475 -100);
DISPLAY 0.617021 (-1475 -100);
PAINT BLUE (-1475 -100);
FORCEPROP 1 LAST VOLTAGE 4V
J 0
(-1475 50);
DISPLAY 0.617021 (-1475 50);
PAINT SKYBLUE (-1475 50);
FORCEPROP 1 LAST VALUE 47UF
J 0
(-1475 100);
DISPLAY 0.617021 (-1475 100);
PAINT SKYBLUE (-1475 100);
FORCEPROP 1 LAST PACK_TYPE 0603V
J 0
(-1475 -150);
DISPLAY 0.617021 (-1475 -150);
PAINT SKYBLUE (-1475 -150);
FORCEPROP 1 LASTPIN (-1525 150) $PN 1
J 0
(-1515 130);
DISPLAY 0.617021 (-1515 130);
PAINT ORANGE (-1515 130);
FORCEPROP 1 LASTPIN (-1525 -50) $PN 2
J 0
(-1515 -70);
DISPLAY 0.617021 (-1515 -70);
PAINT ORANGE (-1515 -70);
FORCEPROP 1 LAST TOLERANCE 20%
J 0
(-1475 0);
DISPLAY 0.617021 (-1475 0);
PAINT SKYBLUE (-1475 0);
FORCEPROP 2 LAST CDS_LOCATION C5U3
J 0
(-1475 150);
DISPLAY 0.617021 (-1475 150);
PAINT AQUA (-1475 150);
DISPLAY INVISIBLE (-1475 150);
FORCEPROP 1 LAST PATH I284
J 0
(-1475 200);
DISPLAY 0.978723 (-1475 200);
PAINT WHITE (-1475 200);
DISPLAY INVISIBLE (-1475 200);
FORCEPROP 2 LAST CDS_LIB dev_discrete
J 0
(-1525 50);
PAINT ORANGE (-1525 50);
DISPLAY INVISIBLE (-1525 50);
FORCEPROP 2 LAST SEC 1
J 0
(-1475 250);
DISPLAY 0.680851 (-1475 250);
PAINT MONO (-1475 250);
DISPLAY INVISIBLE (-1475 250);
FORCEPROP 2 LAST SEC_TYPE 0603V
J 0
(-1475 250);
DISPLAY 1.021277 (-1475 250);
PAINT ORANGE (-1475 250);
DISPLAY INVISIBLE (-1475 250);
FORCEPROP 2 LAST CDS_SEC 1
J 0
(-1475 200);
PAINT ORANGE (-1475 200);
DISPLAY INVISIBLE (-1475 200);
FORCEADD CAP_A..1
(-1225 50);
FORCEPROP 0 LAST BOM_SS E15431-004
J 0
(-1200 -300);
DISPLAY 0.510638 (-1200 -300);
PAINT BROWN (-1200 -300);
DISPLAY BOTH (-1200 -300);
FORCEPROP 1 LAST MATERIAL X5R
J 0
(-1175 -50);
DISPLAY 0.617021 (-1175 -50);
PAINT SKYBLUE (-1175 -50);
FORCEPROP 1 LAST PART_NUMBER 602433-106
J 0
(-1175 -100);
DISPLAY 0.617021 (-1175 -100);
PAINT BLUE (-1175 -100);
FORCEPROP 1 LAST PACK_TYPE 0603V
J 0
(-1175 -150);
DISPLAY 0.617021 (-1175 -150);
PAINT SKYBLUE (-1175 -150);
FORCEPROP 0 LAST GROUP PWR_MLCC_CAP
J 0
(-1169 -188);
DISPLAY 0.638298 (-1169 -188);
PAINT BROWN (-1169 -188);
DISPLAY BOTH (-1169 -188);
FORCEPROP 1 LAST VALUE 47UF
J 0
(-1175 100);
DISPLAY 0.617021 (-1175 100);
PAINT SKYBLUE (-1175 100);
FORCEPROP 1 LAST TOLERANCE 20%
J 0
(-1175 0);
DISPLAY 0.617021 (-1175 0);
PAINT SKYBLUE (-1175 0);
FORCEPROP 1 LAST VOLTAGE 4V
J 0
(-1175 50);
DISPLAY 0.617021 (-1175 50);
PAINT SKYBLUE (-1175 50);
FORCEPROP 1 LAST LOCATION C5U4
J 0
(-1175 150);
DISPLAY 0.617021 (-1175 150);
PAINT AQUA (-1175 150);
FORCEPROP 1 LASTPIN (-1225 150) $PN 1
J 0
(-1215 130);
DISPLAY 0.617021 (-1215 130);
PAINT ORANGE (-1215 130);
FORCEPROP 1 LASTPIN (-1225 -50) $PN 2
J 0
(-1215 -70);
DISPLAY 0.617021 (-1215 -70);
PAINT ORANGE (-1215 -70);
FORCEPROP 2 LAST CDS_LOCATION C5U4
J 0
(-1175 150);
DISPLAY 0.617021 (-1175 150);
PAINT AQUA (-1175 150);
DISPLAY INVISIBLE (-1175 150);
FORCEPROP 1 LAST PATH I285
J 0
(-1175 200);
DISPLAY 0.978723 (-1175 200);
PAINT WHITE (-1175 200);
DISPLAY INVISIBLE (-1175 200);
FORCEPROP 2 LAST CDS_SEC 1
J 0
(-1175 200);
PAINT ORANGE (-1175 200);
DISPLAY INVISIBLE (-1175 200);
FORCEPROP 2 LAST SEC_TYPE 0603V
J 0
(-1175 250);
DISPLAY 1.021277 (-1175 250);
PAINT ORANGE (-1175 250);
DISPLAY INVISIBLE (-1175 250);
FORCEPROP 2 LAST SEC 1
J 0
(-1175 250);
DISPLAY 0.680851 (-1175 250);
PAINT MONO (-1175 250);
DISPLAY INVISIBLE (-1175 250);
FORCEPROP 2 LAST CDS_LIB dev_discrete
J 0
(-1225 50);
PAINT ORANGE (-1225 50);
DISPLAY INVISIBLE (-1225 50);
FORCEADD CAP_A..1
(-950 50);
FORCEPROP 0 LAST BOM_SS E15431-004
J 0
(-925 -350);
DISPLAY 0.510638 (-925 -350);
PAINT BROWN (-925 -350);
DISPLAY BOTH (-925 -350);
FORCEPROP 1 LAST LOCATION C5U5
J 0
(-900 150);
DISPLAY 0.617021 (-900 150);
PAINT AQUA (-900 150);
FORCEPROP 1 LAST VALUE 47UF
J 0
(-900 100);
DISPLAY 0.617021 (-900 100);
PAINT SKYBLUE (-900 100);
FORCEPROP 1 LAST VOLTAGE 4V
J 0
(-900 50);
DISPLAY 0.617021 (-900 50);
PAINT SKYBLUE (-900 50);
FORCEPROP 1 LASTPIN (-950 150) $PN 1
J 0
(-940 130);
DISPLAY 0.617021 (-940 130);
PAINT ORANGE (-940 130);
FORCEPROP 0 LAST GROUP PWR_MLCC_CAP
J 0
(-919 -238);
DISPLAY 0.638298 (-919 -238);
PAINT BROWN (-919 -238);
DISPLAY BOTH (-919 -238);
FORCEPROP 1 LAST PACK_TYPE 0603V
J 0
(-900 -150);
DISPLAY 0.617021 (-900 -150);
PAINT SKYBLUE (-900 -150);
FORCEPROP 1 LAST PART_NUMBER 602433-106
J 0
(-900 -100);
DISPLAY 0.617021 (-900 -100);
PAINT BLUE (-900 -100);
FORCEPROP 1 LAST TOLERANCE 20%
J 0
(-900 0);
DISPLAY 0.617021 (-900 0);
PAINT SKYBLUE (-900 0);
FORCEPROP 1 LAST MATERIAL X5R
J 0
(-900 -50);
DISPLAY 0.617021 (-900 -50);
PAINT SKYBLUE (-900 -50);
FORCEPROP 1 LASTPIN (-950 -50) $PN 2
J 0
(-940 -70);
DISPLAY 0.617021 (-940 -70);
PAINT ORANGE (-940 -70);
FORCEPROP 2 LAST CDS_LOCATION C5U5
J 0
(-900 150);
DISPLAY 0.617021 (-900 150);
PAINT AQUA (-900 150);
DISPLAY INVISIBLE (-900 150);
FORCEPROP 1 LAST PATH I286
J 0
(-900 200);
DISPLAY 0.978723 (-900 200);
PAINT WHITE (-900 200);
DISPLAY INVISIBLE (-900 200);
FORCEPROP 2 LAST CDS_LIB dev_discrete
J 0
(-950 50);
PAINT ORANGE (-950 50);
DISPLAY INVISIBLE (-950 50);
FORCEPROP 2 LAST SEC 1
J 0
(-900 250);
DISPLAY 0.680851 (-900 250);
PAINT MONO (-900 250);
DISPLAY INVISIBLE (-900 250);
FORCEPROP 2 LAST SEC_TYPE 0603V
J 0
(-900 250);
DISPLAY 1.021277 (-900 250);
PAINT ORANGE (-900 250);
DISPLAY INVISIBLE (-900 250);
FORCEPROP 2 LAST CDS_SEC 1
J 0
(-900 200);
PAINT ORANGE (-900 200);
DISPLAY INVISIBLE (-900 200);
FORCEADD CAP_A..1
(-675 50);
FORCEPROP 0 LAST BOM_SS E15431-004
J 0
(-650 -300);
DISPLAY 0.510638 (-650 -300);
PAINT BROWN (-650 -300);
DISPLAY BOTH (-650 -300);
FORCEPROP 1 LAST PART_NUMBER 602433-106
J 0
(-625 -100);
DISPLAY 0.617021 (-625 -100);
PAINT BLUE (-625 -100);
FORCEPROP 0 LAST GROUP PWR_MLCC_CAP
J 0
(-619 -188);
DISPLAY 0.638298 (-619 -188);
PAINT BROWN (-619 -188);
DISPLAY BOTH (-619 -188);
FORCEPROP 1 LAST TOLERANCE 20%
J 0
(-625 0);
DISPLAY 0.617021 (-625 0);
PAINT SKYBLUE (-625 0);
FORCEPROP 1 LAST PACK_TYPE 0603V
J 0
(-625 -150);
DISPLAY 0.617021 (-625 -150);
PAINT SKYBLUE (-625 -150);
FORCEPROP 1 LAST MATERIAL X5R
J 0
(-625 -50);
DISPLAY 0.617021 (-625 -50);
PAINT SKYBLUE (-625 -50);
FORCEPROP 1 LAST VALUE 47UF
J 0
(-625 100);
DISPLAY 0.617021 (-625 100);
PAINT SKYBLUE (-625 100);
FORCEPROP 1 LASTPIN (-675 150) $PN 1
J 0
(-665 130);
DISPLAY 0.617021 (-665 130);
PAINT ORANGE (-665 130);
FORCEPROP 1 LASTPIN (-675 -50) $PN 2
J 0
(-665 -70);
DISPLAY 0.617021 (-665 -70);
PAINT ORANGE (-665 -70);
FORCEPROP 1 LAST VOLTAGE 4V
J 0
(-625 50);
DISPLAY 0.617021 (-625 50);
PAINT SKYBLUE (-625 50);
FORCEPROP 1 LAST LOCATION C5U6
J 0
(-625 150);
DISPLAY 0.617021 (-625 150);
PAINT AQUA (-625 150);
FORCEPROP 2 LAST CDS_LOCATION C5U6
J 0
(-625 150);
DISPLAY 0.617021 (-625 150);
PAINT AQUA (-625 150);
DISPLAY INVISIBLE (-625 150);
FORCEPROP 1 LAST PATH I287
J 0
(-625 200);
DISPLAY 0.978723 (-625 200);
PAINT WHITE (-625 200);
DISPLAY INVISIBLE (-625 200);
FORCEPROP 2 LAST CDS_SEC 1
J 0
(-625 200);
PAINT ORANGE (-625 200);
DISPLAY INVISIBLE (-625 200);
FORCEPROP 2 LAST SEC_TYPE 0603V
J 0
(-625 250);
DISPLAY 1.021277 (-625 250);
PAINT ORANGE (-625 250);
DISPLAY INVISIBLE (-625 250);
FORCEPROP 2 LAST SEC 1
J 0
(-625 250);
DISPLAY 0.680851 (-625 250);
PAINT MONO (-625 250);
DISPLAY INVISIBLE (-625 250);
FORCEPROP 2 LAST CDS_LIB dev_discrete
J 0
(-675 50);
PAINT ORANGE (-675 50);
DISPLAY INVISIBLE (-675 50);
FORCEADD CAP_A..1
(-375 50);
FORCEPROP 1 LASTPIN (-375 -50) $PN 2
J 0
(-365 -70);
DISPLAY 0.617021 (-365 -70);
PAINT ORANGE (-365 -70);
FORCEPROP 1 LAST MATERIAL X5R
J 0
(-325 -50);
DISPLAY 0.617021 (-325 -50);
PAINT SKYBLUE (-325 -50);
FORCEPROP 0 LAST GROUP PWR_MLCC_CAP
J 0
(-319 -238);
DISPLAY 0.638298 (-319 -238);
PAINT BROWN (-319 -238);
DISPLAY BOTH (-319 -238);
FORCEPROP 1 LAST PART_NUMBER 602433-106
J 0
(-325 -100);
DISPLAY 0.617021 (-325 -100);
PAINT BLUE (-325 -100);
FORCEPROP 1 LAST TOLERANCE 20%
J 0
(-325 0);
DISPLAY 0.617021 (-325 0);
PAINT SKYBLUE (-325 0);
FORCEPROP 1 LASTPIN (-375 150) $PN 1
J 0
(-365 130);
DISPLAY 0.617021 (-365 130);
PAINT ORANGE (-365 130);
FORCEPROP 1 LAST LOCATION C5U7
J 0
(-325 150);
DISPLAY 0.617021 (-325 150);
PAINT AQUA (-325 150);
FORCEPROP 1 LAST VALUE 47UF
J 0
(-325 100);
DISPLAY 0.617021 (-325 100);
PAINT SKYBLUE (-325 100);
FORCEPROP 1 LAST VOLTAGE 4V
J 0
(-325 50);
DISPLAY 0.617021 (-325 50);
PAINT SKYBLUE (-325 50);
FORCEPROP 1 LAST PACK_TYPE 0603V
J 0
(-325 -150);
DISPLAY 0.617021 (-325 -150);
PAINT SKYBLUE (-325 -150);
FORCEPROP 0 LAST BOM_SS E15431-004
J 0
(-350 -350);
DISPLAY 0.510638 (-350 -350);
PAINT BROWN (-350 -350);
DISPLAY BOTH (-350 -350);
FORCEPROP 2 LAST CDS_LOCATION C5U7
J 0
(-325 150);
DISPLAY 0.617021 (-325 150);
PAINT AQUA (-325 150);
DISPLAY INVISIBLE (-325 150);
FORCEPROP 1 LAST PATH I288
J 0
(-325 200);
DISPLAY 0.978723 (-325 200);
PAINT WHITE (-325 200);
DISPLAY INVISIBLE (-325 200);
FORCEPROP 2 LAST CDS_LIB dev_discrete
J 0
(-375 50);
PAINT ORANGE (-375 50);
DISPLAY INVISIBLE (-375 50);
FORCEPROP 2 LAST SEC 1
J 0
(-325 250);
DISPLAY 0.680851 (-325 250);
PAINT MONO (-325 250);
DISPLAY INVISIBLE (-325 250);
FORCEPROP 2 LAST SEC_TYPE 0603V
J 0
(-325 250);
DISPLAY 1.021277 (-325 250);
PAINT ORANGE (-325 250);
DISPLAY INVISIBLE (-325 250);
FORCEPROP 2 LAST CDS_SEC 1
J 0
(-325 200);
PAINT ORANGE (-325 200);
DISPLAY INVISIBLE (-325 200);
FORCEADD CAP_A..1
(-75 50);
FORCEPROP 0 LAST BOM_SS E15431-004
J 0
(-50 -300);
DISPLAY 0.510638 (-50 -300);
PAINT BROWN (-50 -300);
DISPLAY BOTH (-50 -300);
FORCEPROP 1 LASTPIN (-75 -50) $PN 2
J 0
(-65 -70);
DISPLAY 0.617021 (-65 -70);
PAINT ORANGE (-65 -70);
FORCEPROP 1 LAST MATERIAL X5R
J 0
(-25 -50);
DISPLAY 0.617021 (-25 -50);
PAINT SKYBLUE (-25 -50);
FORCEPROP 1 LAST TOLERANCE 20%
J 0
(-25 0);
DISPLAY 0.617021 (-25 0);
PAINT SKYBLUE (-25 0);
FORCEPROP 1 LAST VOLTAGE 4V
J 0
(-25 50);
DISPLAY 0.617021 (-25 50);
PAINT SKYBLUE (-25 50);
FORCEPROP 1 LAST VALUE 47UF
J 0
(-25 100);
DISPLAY 0.617021 (-25 100);
PAINT SKYBLUE (-25 100);
FORCEPROP 1 LAST LOCATION C5U8
J 0
(-25 150);
DISPLAY 0.617021 (-25 150);
PAINT AQUA (-25 150);
FORCEPROP 0 LAST GROUP PWR_MLCC_CAP
J 0
(-19 -188);
DISPLAY 0.638298 (-19 -188);
PAINT BROWN (-19 -188);
DISPLAY BOTH (-19 -188);
FORCEPROP 1 LASTPIN (-75 150) $PN 1
J 0
(-65 130);
DISPLAY 0.617021 (-65 130);
PAINT ORANGE (-65 130);
FORCEPROP 1 LAST PACK_TYPE 0603V
J 0
(-25 -150);
DISPLAY 0.617021 (-25 -150);
PAINT SKYBLUE (-25 -150);
FORCEPROP 1 LAST PART_NUMBER 602433-106
J 0
(-25 -100);
DISPLAY 0.617021 (-25 -100);
PAINT BLUE (-25 -100);
FORCEPROP 2 LAST CDS_LOCATION C5U8
J 0
(-25 150);
DISPLAY 0.617021 (-25 150);
PAINT AQUA (-25 150);
DISPLAY INVISIBLE (-25 150);
FORCEPROP 1 LAST PATH I289
J 0
(-25 200);
DISPLAY 0.978723 (-25 200);
PAINT WHITE (-25 200);
DISPLAY INVISIBLE (-25 200);
FORCEPROP 2 LAST CDS_SEC 1
J 0
(-25 200);
PAINT ORANGE (-25 200);
DISPLAY INVISIBLE (-25 200);
FORCEPROP 2 LAST SEC_TYPE 0603V
J 0
(-25 250);
DISPLAY 1.021277 (-25 250);
PAINT ORANGE (-25 250);
DISPLAY INVISIBLE (-25 250);
FORCEPROP 2 LAST SEC 1
J 0
(-25 250);
DISPLAY 0.680851 (-25 250);
PAINT MONO (-25 250);
DISPLAY INVISIBLE (-25 250);
FORCEPROP 2 LAST CDS_LIB dev_discrete
J 0
(-75 50);
PAINT ORANGE (-75 50);
DISPLAY INVISIBLE (-75 50);
FORCEADD CAP_A..1
(200 50);
FORCEPROP 0 LAST BOM_SS E15431-004
J 0
(225 -350);
DISPLAY 0.510638 (225 -350);
PAINT BROWN (225 -350);
DISPLAY BOTH (225 -350);
FORCEPROP 0 LAST GROUP PWR_MLCC_CAP
J 0
(256 -238);
DISPLAY 0.638298 (256 -238);
PAINT BROWN (256 -238);
DISPLAY BOTH (256 -238);
FORCEPROP 1 LAST TOLERANCE 20%
J 0
(250 0);
DISPLAY 0.617021 (250 0);
PAINT SKYBLUE (250 0);
FORCEPROP 1 LAST MATERIAL X5R
J 0
(250 -50);
DISPLAY 0.617021 (250 -50);
PAINT SKYBLUE (250 -50);
FORCEPROP 1 LAST LOCATION C5U9
J 0
(250 150);
DISPLAY 0.617021 (250 150);
PAINT AQUA (250 150);
FORCEPROP 1 LASTPIN (200 -50) $PN 2
J 0
(210 -70);
DISPLAY 0.617021 (210 -70);
PAINT ORANGE (210 -70);
FORCEPROP 1 LASTPIN (200 150) $PN 1
J 0
(210 130);
DISPLAY 0.617021 (210 130);
PAINT ORANGE (210 130);
FORCEPROP 1 LAST VALUE 47UF
J 0
(250 100);
DISPLAY 0.617021 (250 100);
PAINT SKYBLUE (250 100);
FORCEPROP 1 LAST VOLTAGE 4V
J 0
(250 50);
DISPLAY 0.617021 (250 50);
PAINT SKYBLUE (250 50);
FORCEPROP 1 LAST PACK_TYPE 0603V
J 0
(250 -150);
DISPLAY 0.617021 (250 -150);
PAINT SKYBLUE (250 -150);
FORCEPROP 1 LAST PART_NUMBER 602433-106
J 0
(250 -100);
DISPLAY 0.617021 (250 -100);
PAINT BLUE (250 -100);
FORCEPROP 2 LAST CDS_LOCATION C5U9
J 0
(250 150);
DISPLAY 0.617021 (250 150);
PAINT AQUA (250 150);
DISPLAY INVISIBLE (250 150);
FORCEPROP 1 LAST PATH I290
J 0
(250 200);
DISPLAY 0.978723 (250 200);
PAINT WHITE (250 200);
DISPLAY INVISIBLE (250 200);
FORCEPROP 2 LAST CDS_LIB dev_discrete
J 0
(200 50);
PAINT ORANGE (200 50);
DISPLAY INVISIBLE (200 50);
FORCEPROP 2 LAST SEC 1
J 0
(250 250);
DISPLAY 0.680851 (250 250);
PAINT MONO (250 250);
DISPLAY INVISIBLE (250 250);
FORCEPROP 2 LAST SEC_TYPE 0603V
J 0
(250 250);
DISPLAY 1.021277 (250 250);
PAINT ORANGE (250 250);
DISPLAY INVISIBLE (250 250);
FORCEPROP 2 LAST CDS_SEC 1
J 0
(250 200);
PAINT ORANGE (250 200);
DISPLAY INVISIBLE (250 200);
FORCEADD CAP_A..1
(525 50);
FORCEPROP 0 LAST BOM_SS E15431-004
J 0
(550 -300);
DISPLAY 0.510638 (550 -300);
PAINT BROWN (550 -300);
DISPLAY BOTH (550 -300);
FORCEPROP 0 LAST GROUP PWR_MLCC_CAP
J 0
(581 -188);
DISPLAY 0.638298 (581 -188);
PAINT BROWN (581 -188);
DISPLAY BOTH (581 -188);
FORCEPROP 1 LAST TOLERANCE 20%
J 0
(575 0);
DISPLAY 0.617021 (575 0);
PAINT SKYBLUE (575 0);
FORCEPROP 1 LAST LOCATION C5T12
J 0
(575 150);
DISPLAY 0.617021 (575 150);
PAINT AQUA (575 150);
FORCEPROP 1 LAST MATERIAL X5R
J 0
(575 -50);
DISPLAY 0.617021 (575 -50);
PAINT SKYBLUE (575 -50);
FORCEPROP 1 LASTPIN (525 -50) $PN 2
J 0
(535 -70);
DISPLAY 0.617021 (535 -70);
PAINT ORANGE (535 -70);
FORCEPROP 1 LASTPIN (525 150) $PN 1
J 0
(535 130);
DISPLAY 0.617021 (535 130);
PAINT ORANGE (535 130);
FORCEPROP 1 LAST VOLTAGE 4V
J 0
(575 50);
DISPLAY 0.617021 (575 50);
PAINT SKYBLUE (575 50);
FORCEPROP 1 LAST PACK_TYPE 0603V
J 0
(575 -150);
DISPLAY 0.617021 (575 -150);
PAINT SKYBLUE (575 -150);
FORCEPROP 1 LAST PART_NUMBER 602433-106
J 0
(575 -100);
DISPLAY 0.617021 (575 -100);
PAINT BLUE (575 -100);
FORCEPROP 1 LAST VALUE 47UF
J 0
(575 100);
DISPLAY 0.617021 (575 100);
PAINT SKYBLUE (575 100);
FORCEPROP 2 LAST CDS_LOCATION C5T12
J 0
(575 150);
DISPLAY 0.617021 (575 150);
PAINT AQUA (575 150);
DISPLAY INVISIBLE (575 150);
FORCEPROP 1 LAST PATH I291
J 0
(575 200);
DISPLAY 0.978723 (575 200);
PAINT WHITE (575 200);
DISPLAY INVISIBLE (575 200);
FORCEPROP 2 LAST CDS_LIB dev_discrete
J 0
(525 50);
PAINT ORANGE (525 50);
DISPLAY INVISIBLE (525 50);
FORCEPROP 2 LAST SEC 1
J 0
(575 250);
DISPLAY 0.680851 (575 250);
PAINT MONO (575 250);
DISPLAY INVISIBLE (575 250);
FORCEPROP 2 LAST SEC_TYPE 0603V
J 0
(575 250);
DISPLAY 1.021277 (575 250);
PAINT ORANGE (575 250);
DISPLAY INVISIBLE (575 250);
FORCEPROP 2 LAST CDS_SEC 1
J 0
(575 200);
PAINT ORANGE (575 200);
DISPLAY INVISIBLE (575 200);
FORCEADD CAP_A..1
(825 50);
FORCEPROP 0 LAST BOM_SS E15431-004
J 0
(850 -350);
DISPLAY 0.510638 (850 -350);
PAINT BROWN (850 -350);
DISPLAY BOTH (850 -350);
FORCEPROP 1 LAST MATERIAL X5R
J 0
(875 -50);
DISPLAY 0.617021 (875 -50);
PAINT SKYBLUE (875 -50);
FORCEPROP 1 LAST TOLERANCE 20%
J 0
(875 0);
DISPLAY 0.617021 (875 0);
PAINT SKYBLUE (875 0);
FORCEPROP 0 LAST GROUP PWR_MLCC_CAP
J 0
(881 -238);
DISPLAY 0.638298 (881 -238);
PAINT BROWN (881 -238);
DISPLAY BOTH (881 -238);
FORCEPROP 1 LAST LOCATION C5T11
J 0
(875 150);
DISPLAY 0.617021 (875 150);
PAINT AQUA (875 150);
FORCEPROP 1 LAST VOLTAGE 4V
J 0
(875 50);
DISPLAY 0.617021 (875 50);
PAINT SKYBLUE (875 50);
FORCEPROP 1 LAST VALUE 47UF
J 0
(875 100);
DISPLAY 0.617021 (875 100);
PAINT SKYBLUE (875 100);
FORCEPROP 1 LASTPIN (825 150) $PN 1
J 0
(835 130);
DISPLAY 0.617021 (835 130);
PAINT ORANGE (835 130);
FORCEPROP 1 LAST PACK_TYPE 0603V
J 0
(875 -150);
DISPLAY 0.617021 (875 -150);
PAINT SKYBLUE (875 -150);
FORCEPROP 1 LASTPIN (825 -50) $PN 2
J 0
(835 -70);
DISPLAY 0.617021 (835 -70);
PAINT ORANGE (835 -70);
FORCEPROP 1 LAST PART_NUMBER 602433-106
J 0
(875 -100);
DISPLAY 0.617021 (875 -100);
PAINT BLUE (875 -100);
FORCEPROP 2 LAST CDS_LOCATION C5T11
J 0
(875 150);
DISPLAY 0.617021 (875 150);
PAINT AQUA (875 150);
DISPLAY INVISIBLE (875 150);
FORCEPROP 1 LAST PATH I292
J 0
(875 200);
DISPLAY 0.978723 (875 200);
PAINT WHITE (875 200);
DISPLAY INVISIBLE (875 200);
FORCEPROP 2 LAST CDS_SEC 1
J 0
(875 200);
PAINT ORANGE (875 200);
DISPLAY INVISIBLE (875 200);
FORCEPROP 2 LAST SEC_TYPE 0603V
J 0
(875 250);
DISPLAY 1.021277 (875 250);
PAINT ORANGE (875 250);
DISPLAY INVISIBLE (875 250);
FORCEPROP 2 LAST SEC 1
J 0
(875 250);
DISPLAY 0.680851 (875 250);
PAINT MONO (875 250);
DISPLAY INVISIBLE (875 250);
FORCEPROP 2 LAST CDS_LIB dev_discrete
J 0
(825 50);
PAINT ORANGE (825 50);
DISPLAY INVISIBLE (825 50);
FORCEADD CAP_A..1
(1125 50);
FORCEPROP 0 LAST BOM_SS E15431-004
J 0
(1150 -300);
DISPLAY 0.510638 (1150 -300);
PAINT BROWN (1150 -300);
DISPLAY BOTH (1150 -300);
FORCEPROP 1 LAST LOCATION C5T10
J 0
(1175 150);
DISPLAY 0.617021 (1175 150);
PAINT AQUA (1175 150);
FORCEPROP 1 LAST TOLERANCE 20%
J 0
(1175 0);
DISPLAY 0.617021 (1175 0);
PAINT SKYBLUE (1175 0);
FORCEPROP 0 LAST GROUP PWR_MLCC_CAP
J 0
(1181 -188);
DISPLAY 0.638298 (1181 -188);
PAINT BROWN (1181 -188);
DISPLAY BOTH (1181 -188);
FORCEPROP 1 LASTPIN (1125 150) $PN 1
J 0
(1135 130);
DISPLAY 0.617021 (1135 130);
PAINT ORANGE (1135 130);
FORCEPROP 1 LAST VOLTAGE 4V
J 0
(1175 50);
DISPLAY 0.617021 (1175 50);
PAINT SKYBLUE (1175 50);
FORCEPROP 1 LAST VALUE 47UF
J 0
(1175 100);
DISPLAY 0.617021 (1175 100);
PAINT SKYBLUE (1175 100);
FORCEPROP 1 LASTPIN (1125 -50) $PN 2
J 0
(1135 -70);
DISPLAY 0.617021 (1135 -70);
PAINT ORANGE (1135 -70);
FORCEPROP 1 LAST MATERIAL X5R
J 0
(1175 -50);
DISPLAY 0.617021 (1175 -50);
PAINT SKYBLUE (1175 -50);
FORCEPROP 1 LAST PART_NUMBER 602433-106
J 0
(1175 -100);
DISPLAY 0.617021 (1175 -100);
PAINT BLUE (1175 -100);
FORCEPROP 1 LAST PACK_TYPE 0603V
J 0
(1175 -150);
DISPLAY 0.617021 (1175 -150);
PAINT SKYBLUE (1175 -150);
FORCEPROP 2 LAST CDS_LOCATION C5T10
J 0
(1175 150);
DISPLAY 0.617021 (1175 150);
PAINT AQUA (1175 150);
DISPLAY INVISIBLE (1175 150);
FORCEPROP 1 LAST PATH I293
J 0
(1175 200);
DISPLAY 0.978723 (1175 200);
PAINT WHITE (1175 200);
DISPLAY INVISIBLE (1175 200);
FORCEPROP 2 LAST CDS_LIB dev_discrete
J 0
(1125 50);
PAINT ORANGE (1125 50);
DISPLAY INVISIBLE (1125 50);
FORCEPROP 2 LAST SEC 1
J 0
(1175 250);
DISPLAY 0.680851 (1175 250);
PAINT MONO (1175 250);
DISPLAY INVISIBLE (1175 250);
FORCEPROP 2 LAST SEC_TYPE 0603V
J 0
(1175 250);
DISPLAY 1.021277 (1175 250);
PAINT ORANGE (1175 250);
DISPLAY INVISIBLE (1175 250);
FORCEPROP 2 LAST CDS_SEC 1
J 0
(1175 200);
PAINT ORANGE (1175 200);
DISPLAY INVISIBLE (1175 200);
FORCEADD CAP_A..1
(1400 50);
FORCEPROP 0 LAST BOM_SS E15431-004
J 0
(1425 -350);
DISPLAY 0.510638 (1425 -350);
PAINT BROWN (1425 -350);
DISPLAY BOTH (1425 -350);
FORCEPROP 1 LAST TOLERANCE 20%
J 0
(1450 0);
DISPLAY 0.617021 (1450 0);
PAINT SKYBLUE (1450 0);
FORCEPROP 0 LAST GROUP PWR_MLCC_CAP
J 0
(1456 -238);
DISPLAY 0.638298 (1456 -238);
PAINT BROWN (1456 -238);
DISPLAY BOTH (1456 -238);
FORCEPROP 1 LAST PACK_TYPE 0603V
J 0
(1450 -150);
DISPLAY 0.617021 (1450 -150);
PAINT SKYBLUE (1450 -150);
FORCEPROP 1 LAST PART_NUMBER 602433-106
J 0
(1450 -100);
DISPLAY 0.617021 (1450 -100);
PAINT BLUE (1450 -100);
FORCEPROP 1 LAST VOLTAGE 4V
J 0
(1450 50);
DISPLAY 0.617021 (1450 50);
PAINT SKYBLUE (1450 50);
FORCEPROP 1 LAST VALUE 47UF
J 0
(1450 100);
DISPLAY 0.617021 (1450 100);
PAINT SKYBLUE (1450 100);
FORCEPROP 1 LASTPIN (1400 150) $PN 1
J 0
(1410 130);
DISPLAY 0.617021 (1410 130);
PAINT ORANGE (1410 130);
FORCEPROP 1 LAST LOCATION C5T9
J 0
(1450 150);
DISPLAY 0.617021 (1450 150);
PAINT AQUA (1450 150);
FORCEPROP 1 LASTPIN (1400 -50) $PN 2
J 0
(1410 -70);
DISPLAY 0.617021 (1410 -70);
PAINT ORANGE (1410 -70);
FORCEPROP 1 LAST MATERIAL X5R
J 0
(1450 -50);
DISPLAY 0.617021 (1450 -50);
PAINT SKYBLUE (1450 -50);
FORCEPROP 2 LAST CDS_LOCATION C5T9
J 0
(1450 150);
DISPLAY 0.617021 (1450 150);
PAINT AQUA (1450 150);
DISPLAY INVISIBLE (1450 150);
FORCEPROP 1 LAST PATH I294
J 0
(1450 200);
DISPLAY 0.978723 (1450 200);
PAINT WHITE (1450 200);
DISPLAY INVISIBLE (1450 200);
FORCEPROP 2 LAST CDS_SEC 1
J 0
(1450 200);
PAINT ORANGE (1450 200);
DISPLAY INVISIBLE (1450 200);
FORCEPROP 2 LAST SEC_TYPE 0603V
J 0
(1450 250);
DISPLAY 1.021277 (1450 250);
PAINT ORANGE (1450 250);
DISPLAY INVISIBLE (1450 250);
FORCEPROP 2 LAST SEC 1
J 0
(1450 250);
DISPLAY 0.680851 (1450 250);
PAINT MONO (1450 250);
DISPLAY INVISIBLE (1450 250);
FORCEPROP 2 LAST CDS_LIB dev_discrete
J 0
(1400 50);
PAINT ORANGE (1400 50);
DISPLAY INVISIBLE (1400 50);
FORCEADD CAP_A..1
(1675 50);
FORCEPROP 0 LAST BOM_SS E15431-004
J 0
(1700 -300);
DISPLAY 0.510638 (1700 -300);
PAINT BROWN (1700 -300);
DISPLAY BOTH (1700 -300);
FORCEPROP 1 LAST TOLERANCE 20%
J 0
(1725 0);
DISPLAY 0.617021 (1725 0);
PAINT SKYBLUE (1725 0);
FORCEPROP 0 LAST GROUP PWR_MLCC_CAP
J 0
(1731 -188);
DISPLAY 0.638298 (1731 -188);
PAINT BROWN (1731 -188);
DISPLAY BOTH (1731 -188);
FORCEPROP 1 LAST PACK_TYPE 0603V
J 0
(1725 -150);
DISPLAY 0.617021 (1725 -150);
PAINT SKYBLUE (1725 -150);
FORCEPROP 1 LAST VALUE 47UF
J 0
(1725 100);
DISPLAY 0.617021 (1725 100);
PAINT SKYBLUE (1725 100);
FORCEPROP 1 LAST VOLTAGE 4V
J 0
(1725 50);
DISPLAY 0.617021 (1725 50);
PAINT SKYBLUE (1725 50);
FORCEPROP 1 LAST LOCATION C5T8
J 0
(1725 150);
DISPLAY 0.617021 (1725 150);
PAINT AQUA (1725 150);
FORCEPROP 1 LASTPIN (1675 150) $PN 1
J 0
(1685 130);
DISPLAY 0.617021 (1685 130);
PAINT ORANGE (1685 130);
FORCEPROP 1 LAST PART_NUMBER 602433-106
J 0
(1725 -100);
DISPLAY 0.617021 (1725 -100);
PAINT BLUE (1725 -100);
FORCEPROP 1 LASTPIN (1675 -50) $PN 2
J 0
(1685 -70);
DISPLAY 0.617021 (1685 -70);
PAINT ORANGE (1685 -70);
FORCEPROP 1 LAST MATERIAL X5R
J 0
(1725 -50);
DISPLAY 0.617021 (1725 -50);
PAINT SKYBLUE (1725 -50);
FORCEPROP 2 LAST CDS_LOCATION C5T8
J 0
(1725 150);
DISPLAY 0.617021 (1725 150);
PAINT AQUA (1725 150);
DISPLAY INVISIBLE (1725 150);
FORCEPROP 1 LAST PATH I295
J 0
(1725 200);
DISPLAY 0.978723 (1725 200);
PAINT WHITE (1725 200);
DISPLAY INVISIBLE (1725 200);
FORCEPROP 2 LAST CDS_LIB dev_discrete
J 0
(1675 50);
PAINT ORANGE (1675 50);
DISPLAY INVISIBLE (1675 50);
FORCEPROP 2 LAST SEC 1
J 0
(1725 250);
DISPLAY 0.680851 (1725 250);
PAINT MONO (1725 250);
DISPLAY INVISIBLE (1725 250);
FORCEPROP 2 LAST SEC_TYPE 0603V
J 0
(1725 250);
DISPLAY 1.021277 (1725 250);
PAINT ORANGE (1725 250);
DISPLAY INVISIBLE (1725 250);
FORCEPROP 2 LAST CDS_SEC 1
J 0
(1725 200);
PAINT ORANGE (1725 200);
DISPLAY INVISIBLE (1725 200);
FORCEADD CAP_A..1
(1975 50);
FORCEPROP 0 LAST BOM_SS E15431-004
J 0
(2000 -350);
DISPLAY 0.510638 (2000 -350);
PAINT BROWN (2000 -350);
DISPLAY BOTH (2000 -350);
FORCEPROP 1 LAST TOLERANCE 20%
J 0
(2025 0);
DISPLAY 0.617021 (2025 0);
PAINT SKYBLUE (2025 0);
FORCEPROP 0 LAST GROUP PWR_MLCC_CAP
J 0
(2031 -238);
DISPLAY 0.638298 (2031 -238);
PAINT BROWN (2031 -238);
DISPLAY BOTH (2031 -238);
FORCEPROP 1 LAST LOCATION C5T7
J 0
(2025 150);
DISPLAY 0.617021 (2025 150);
PAINT AQUA (2025 150);
FORCEPROP 1 LASTPIN (1975 150) $PN 1
J 0
(1985 130);
DISPLAY 0.617021 (1985 130);
PAINT ORANGE (1985 130);
FORCEPROP 1 LAST VALUE 47UF
J 0
(2025 100);
DISPLAY 0.617021 (2025 100);
PAINT SKYBLUE (2025 100);
FORCEPROP 1 LAST VOLTAGE 4V
J 0
(2025 50);
DISPLAY 0.617021 (2025 50);
PAINT SKYBLUE (2025 50);
FORCEPROP 1 LASTPIN (1975 -50) $PN 2
J 0
(1985 -70);
DISPLAY 0.617021 (1985 -70);
PAINT ORANGE (1985 -70);
FORCEPROP 1 LAST MATERIAL X5R
J 0
(2025 -50);
DISPLAY 0.617021 (2025 -50);
PAINT SKYBLUE (2025 -50);
FORCEPROP 1 LAST PACK_TYPE 0603V
J 0
(2025 -150);
DISPLAY 0.617021 (2025 -150);
PAINT SKYBLUE (2025 -150);
FORCEPROP 1 LAST PART_NUMBER 602433-106
J 0
(2025 -100);
DISPLAY 0.617021 (2025 -100);
PAINT BLUE (2025 -100);
FORCEPROP 2 LAST CDS_LOCATION C5T7
J 0
(2025 150);
DISPLAY 0.617021 (2025 150);
PAINT AQUA (2025 150);
DISPLAY INVISIBLE (2025 150);
FORCEPROP 1 LAST PATH I296
J 0
(2025 200);
DISPLAY 0.978723 (2025 200);
PAINT WHITE (2025 200);
DISPLAY INVISIBLE (2025 200);
FORCEPROP 2 LAST CDS_SEC 1
J 0
(2025 200);
PAINT ORANGE (2025 200);
DISPLAY INVISIBLE (2025 200);
FORCEPROP 2 LAST SEC_TYPE 0603V
J 0
(2025 250);
DISPLAY 1.021277 (2025 250);
PAINT ORANGE (2025 250);
DISPLAY INVISIBLE (2025 250);
FORCEPROP 2 LAST SEC 1
J 0
(2025 250);
DISPLAY 0.680851 (2025 250);
PAINT MONO (2025 250);
DISPLAY INVISIBLE (2025 250);
FORCEPROP 2 LAST CDS_LIB dev_discrete
J 0
(1975 50);
PAINT ORANGE (1975 50);
DISPLAY INVISIBLE (1975 50);
FORCEADD CAP_A..1
(2275 50);
FORCEPROP 0 LAST BOM_SS E15431-004
J 0
(2300 -300);
DISPLAY 0.510638 (2300 -300);
PAINT BROWN (2300 -300);
DISPLAY BOTH (2300 -300);
FORCEPROP 1 LAST PACK_TYPE 0603V
J 0
(2325 -150);
DISPLAY 0.617021 (2325 -150);
PAINT SKYBLUE (2325 -150);
FORCEPROP 1 LAST TOLERANCE 20%
J 0
(2325 0);
DISPLAY 0.617021 (2325 0);
PAINT SKYBLUE (2325 0);
FORCEPROP 0 LAST GROUP PWR_MLCC_CAP
J 0
(2331 -188);
DISPLAY 0.638298 (2331 -188);
PAINT BROWN (2331 -188);
DISPLAY BOTH (2331 -188);
FORCEPROP 1 LAST LOCATION C5T6
J 0
(2325 150);
DISPLAY 0.617021 (2325 150);
PAINT AQUA (2325 150);
FORCEPROP 1 LASTPIN (2275 150) $PN 1
J 0
(2285 130);
DISPLAY 0.617021 (2285 130);
PAINT ORANGE (2285 130);
FORCEPROP 1 LAST VOLTAGE 4V
J 0
(2325 50);
DISPLAY 0.617021 (2325 50);
PAINT SKYBLUE (2325 50);
FORCEPROP 1 LAST VALUE 47UF
J 0
(2325 100);
DISPLAY 0.617021 (2325 100);
PAINT SKYBLUE (2325 100);
FORCEPROP 1 LAST MATERIAL X5R
J 0
(2325 -50);
DISPLAY 0.617021 (2325 -50);
PAINT SKYBLUE (2325 -50);
FORCEPROP 1 LAST PART_NUMBER 602433-106
J 0
(2325 -100);
DISPLAY 0.617021 (2325 -100);
PAINT BLUE (2325 -100);
FORCEPROP 1 LASTPIN (2275 -50) $PN 2
J 0
(2285 -70);
DISPLAY 0.617021 (2285 -70);
PAINT ORANGE (2285 -70);
FORCEPROP 2 LAST CDS_LOCATION C5T6
J 0
(2325 150);
DISPLAY 0.617021 (2325 150);
PAINT AQUA (2325 150);
DISPLAY INVISIBLE (2325 150);
FORCEPROP 1 LAST PATH I297
J 0
(2325 200);
DISPLAY 0.978723 (2325 200);
PAINT WHITE (2325 200);
DISPLAY INVISIBLE (2325 200);
FORCEPROP 2 LAST CDS_LIB dev_discrete
J 0
(2275 50);
PAINT ORANGE (2275 50);
DISPLAY INVISIBLE (2275 50);
FORCEPROP 2 LAST SEC 1
J 0
(2325 250);
DISPLAY 0.680851 (2325 250);
PAINT MONO (2325 250);
DISPLAY INVISIBLE (2325 250);
FORCEPROP 2 LAST SEC_TYPE 0603V
J 0
(2325 250);
DISPLAY 1.021277 (2325 250);
PAINT ORANGE (2325 250);
DISPLAY INVISIBLE (2325 250);
FORCEPROP 2 LAST CDS_SEC 1
J 0
(2325 200);
PAINT ORANGE (2325 200);
DISPLAY INVISIBLE (2325 200);
FORCEADD CAP_A..1
(2550 50);
FORCEPROP 0 LAST BOM_SS E15431-004
J 0
(2575 -350);
DISPLAY 0.510638 (2575 -350);
PAINT BROWN (2575 -350);
DISPLAY BOTH (2575 -350);
FORCEPROP 1 LAST TOLERANCE 20%
J 0
(2600 0);
DISPLAY 0.617021 (2600 0);
PAINT SKYBLUE (2600 0);
FORCEPROP 0 LAST GROUP PWR_MLCC_CAP
J 0
(2606 -238);
DISPLAY 0.638298 (2606 -238);
PAINT BROWN (2606 -238);
DISPLAY BOTH (2606 -238);
FORCEPROP 1 LASTPIN (2550 -50) $PN 2
J 0
(2560 -70);
DISPLAY 0.617021 (2560 -70);
PAINT ORANGE (2560 -70);
FORCEPROP 1 LAST PACK_TYPE 0603V
J 0
(2600 -150);
DISPLAY 0.617021 (2600 -150);
PAINT SKYBLUE (2600 -150);
FORCEPROP 1 LAST PART_NUMBER 602433-106
J 0
(2600 -100);
DISPLAY 0.617021 (2600 -100);
PAINT BLUE (2600 -100);
FORCEPROP 1 LASTPIN (2550 150) $PN 1
J 0
(2560 130);
DISPLAY 0.617021 (2560 130);
PAINT ORANGE (2560 130);
FORCEPROP 1 LAST VOLTAGE 4V
J 0
(2600 50);
DISPLAY 0.617021 (2600 50);
PAINT SKYBLUE (2600 50);
FORCEPROP 1 LAST MATERIAL X5R
J 0
(2600 -50);
DISPLAY 0.617021 (2600 -50);
PAINT SKYBLUE (2600 -50);
FORCEPROP 1 LAST VALUE 47UF
J 0
(2600 100);
DISPLAY 0.617021 (2600 100);
PAINT SKYBLUE (2600 100);
FORCEPROP 1 LAST LOCATION C5T5
J 0
(2600 150);
DISPLAY 0.617021 (2600 150);
PAINT AQUA (2600 150);
FORCEPROP 2 LAST CDS_LOCATION C5T5
J 0
(2600 150);
DISPLAY 0.617021 (2600 150);
PAINT AQUA (2600 150);
DISPLAY INVISIBLE (2600 150);
FORCEPROP 2 LAST CDS_LIB dev_discrete
J 0
(2550 50);
PAINT ORANGE (2550 50);
DISPLAY INVISIBLE (2550 50);
FORCEPROP 2 LAST SEC 1
J 0
(2600 250);
DISPLAY 0.680851 (2600 250);
PAINT MONO (2600 250);
DISPLAY INVISIBLE (2600 250);
FORCEPROP 2 LAST SEC_TYPE 0603V
J 0
(2600 250);
DISPLAY 1.021277 (2600 250);
PAINT ORANGE (2600 250);
DISPLAY INVISIBLE (2600 250);
FORCEPROP 2 LAST CDS_SEC 1
J 0
(2600 200);
PAINT ORANGE (2600 200);
DISPLAY INVISIBLE (2600 200);
FORCEPROP 1 LAST PATH I298
J 0
(2600 200);
DISPLAY 0.978723 (2600 200);
PAINT WHITE (2600 200);
DISPLAY INVISIBLE (2600 200);
FORCEADD CAP_A..1
(-1825 -650);
FORCEPROP 0 LAST BOM_SS E15431-004
J 0
(-1800 -1000);
DISPLAY 0.510638 (-1800 -1000);
PAINT BROWN (-1800 -1000);
DISPLAY BOTH (-1800 -1000);
FORCEPROP 0 LAST GROUP PWR_MLCC_CAP
J 0
(-1769 -888);
DISPLAY 0.638298 (-1769 -888);
PAINT BROWN (-1769 -888);
DISPLAY BOTH (-1769 -888);
FORCEPROP 1 LAST TOLERANCE 20%
J 0
(-1775 -700);
DISPLAY 0.617021 (-1775 -700);
PAINT SKYBLUE (-1775 -700);
FORCEPROP 1 LAST PART_NUMBER 602433-106
J 0
(-1775 -800);
DISPLAY 0.617021 (-1775 -800);
PAINT BLUE (-1775 -800);
FORCEPROP 1 LAST PACK_TYPE 0603V
J 0
(-1775 -850);
DISPLAY 0.617021 (-1775 -850);
PAINT SKYBLUE (-1775 -850);
FORCEPROP 1 LAST VOLTAGE 4V
J 0
(-1775 -650);
DISPLAY 0.617021 (-1775 -650);
PAINT SKYBLUE (-1775 -650);
FORCEPROP 1 LASTPIN (-1825 -750) $PN 2
J 0
(-1815 -770);
DISPLAY 0.617021 (-1815 -770);
PAINT ORANGE (-1815 -770);
FORCEPROP 1 LAST MATERIAL X5R
J 0
(-1775 -750);
DISPLAY 0.617021 (-1775 -750);
PAINT SKYBLUE (-1775 -750);
FORCEPROP 1 LAST VALUE 47UF
J 0
(-1775 -600);
DISPLAY 0.617021 (-1775 -600);
PAINT SKYBLUE (-1775 -600);
FORCEPROP 1 LAST LOCATION C5G11
J 0
(-1775 -550);
DISPLAY 0.617021 (-1775 -550);
PAINT AQUA (-1775 -550);
FORCEPROP 1 LASTPIN (-1825 -550) $PN 1
J 0
(-1815 -570);
DISPLAY 0.617021 (-1815 -570);
PAINT ORANGE (-1815 -570);
FORCEPROP 2 LAST CDS_LOCATION C5G11
J 0
(-1775 -550);
DISPLAY 0.617021 (-1775 -550);
PAINT AQUA (-1775 -550);
DISPLAY INVISIBLE (-1775 -550);
FORCEPROP 1 LAST PATH I299
J 0
(-1775 -500);
DISPLAY 0.978723 (-1775 -500);
PAINT WHITE (-1775 -500);
DISPLAY INVISIBLE (-1775 -500);
FORCEPROP 2 LAST CDS_SEC 1
J 0
(-1775 -500);
PAINT ORANGE (-1775 -500);
DISPLAY INVISIBLE (-1775 -500);
FORCEPROP 2 LAST SEC_TYPE 0603V
J 0
(-1775 -450);
DISPLAY 1.021277 (-1775 -450);
PAINT ORANGE (-1775 -450);
DISPLAY INVISIBLE (-1775 -450);
FORCEPROP 2 LAST SEC 1
J 0
(-1775 -450);
DISPLAY 0.680851 (-1775 -450);
PAINT MONO (-1775 -450);
DISPLAY INVISIBLE (-1775 -450);
FORCEPROP 2 LAST CDS_LIB dev_discrete
J 0
(-1825 -650);
PAINT ORANGE (-1825 -650);
DISPLAY INVISIBLE (-1825 -650);
FORCEADD CAP_A..1
(-1525 -650);
FORCEPROP 1 LASTPIN (-1525 -550) $PN 1
J 0
(-1515 -570);
DISPLAY 0.617021 (-1515 -570);
PAINT ORANGE (-1515 -570);
FORCEPROP 0 LAST BOM_SS E15431-004
J 0
(-1525 -1050);
DISPLAY 0.510638 (-1525 -1050);
PAINT BROWN (-1525 -1050);
DISPLAY BOTH (-1525 -1050);
FORCEPROP 0 LAST GROUP PWR_MLCC_CAP
J 0
(-1469 -938);
DISPLAY 0.638298 (-1469 -938);
PAINT BROWN (-1469 -938);
DISPLAY BOTH (-1469 -938);
FORCEPROP 1 LAST TOLERANCE 20%
J 0
(-1475 -700);
DISPLAY 0.617021 (-1475 -700);
PAINT SKYBLUE (-1475 -700);
FORCEPROP 1 LAST VOLTAGE 4V
J 0
(-1475 -650);
DISPLAY 0.617021 (-1475 -650);
PAINT SKYBLUE (-1475 -650);
FORCEPROP 1 LAST MATERIAL X5R
J 0
(-1475 -750);
DISPLAY 0.617021 (-1475 -750);
PAINT SKYBLUE (-1475 -750);
FORCEPROP 1 LAST PART_NUMBER 602433-106
J 0
(-1475 -800);
DISPLAY 0.617021 (-1475 -800);
PAINT BLUE (-1475 -800);
FORCEPROP 1 LAST PACK_TYPE 0603V
J 0
(-1475 -850);
DISPLAY 0.617021 (-1475 -850);
PAINT SKYBLUE (-1475 -850);
FORCEPROP 1 LASTPIN (-1525 -750) $PN 2
J 0
(-1515 -770);
DISPLAY 0.617021 (-1515 -770);
PAINT ORANGE (-1515 -770);
FORCEPROP 1 LAST LOCATION C5G12
J 0
(-1475 -550);
DISPLAY 0.617021 (-1475 -550);
PAINT AQUA (-1475 -550);
FORCEPROP 1 LAST VALUE 47UF
J 0
(-1475 -600);
DISPLAY 0.617021 (-1475 -600);
PAINT SKYBLUE (-1475 -600);
FORCEPROP 2 LAST CDS_LOCATION C5G12
J 0
(-1475 -550);
DISPLAY 0.617021 (-1475 -550);
PAINT AQUA (-1475 -550);
DISPLAY INVISIBLE (-1475 -550);
FORCEPROP 1 LAST PATH I300
J 0
(-1475 -500);
DISPLAY 0.978723 (-1475 -500);
PAINT WHITE (-1475 -500);
DISPLAY INVISIBLE (-1475 -500);
FORCEPROP 2 LAST CDS_SEC 1
J 0
(-1475 -500);
PAINT ORANGE (-1475 -500);
DISPLAY INVISIBLE (-1475 -500);
FORCEPROP 2 LAST SEC_TYPE 0603V
J 0
(-1475 -450);
DISPLAY 1.021277 (-1475 -450);
PAINT ORANGE (-1475 -450);
DISPLAY INVISIBLE (-1475 -450);
FORCEPROP 2 LAST SEC 1
J 0
(-1475 -450);
DISPLAY 0.680851 (-1475 -450);
PAINT MONO (-1475 -450);
DISPLAY INVISIBLE (-1475 -450);
FORCEPROP 2 LAST CDS_LIB dev_discrete
J 0
(-1525 -650);
PAINT ORANGE (-1525 -650);
DISPLAY INVISIBLE (-1525 -650);
FORCEADD CAP_A..1
(-1225 -650);
FORCEPROP 0 LAST BOM_SS E15431-004
J 0
(-1225 -1000);
DISPLAY 0.510638 (-1225 -1000);
PAINT BROWN (-1225 -1000);
DISPLAY BOTH (-1225 -1000);
FORCEPROP 0 LAST GROUP PWR_MLCC_CAP
J 0
(-1169 -888);
DISPLAY 0.638298 (-1169 -888);
PAINT BROWN (-1169 -888);
DISPLAY BOTH (-1169 -888);
FORCEPROP 1 LAST TOLERANCE 20%
J 0
(-1175 -700);
DISPLAY 0.617021 (-1175 -700);
PAINT SKYBLUE (-1175 -700);
FORCEPROP 1 LAST PART_NUMBER 602433-106
J 0
(-1175 -800);
DISPLAY 0.617021 (-1175 -800);
PAINT BLUE (-1175 -800);
FORCEPROP 1 LASTPIN (-1225 -750) $PN 2
J 0
(-1215 -770);
DISPLAY 0.617021 (-1215 -770);
PAINT ORANGE (-1215 -770);
FORCEPROP 1 LASTPIN (-1225 -550) $PN 1
J 0
(-1215 -570);
DISPLAY 0.617021 (-1215 -570);
PAINT ORANGE (-1215 -570);
FORCEPROP 1 LAST PACK_TYPE 0603V
J 0
(-1175 -850);
DISPLAY 0.617021 (-1175 -850);
PAINT SKYBLUE (-1175 -850);
FORCEPROP 1 LAST LOCATION C5G2
J 0
(-1175 -550);
DISPLAY 0.617021 (-1175 -550);
PAINT AQUA (-1175 -550);
FORCEPROP 1 LAST VALUE 47UF
J 0
(-1175 -600);
DISPLAY 0.617021 (-1175 -600);
PAINT SKYBLUE (-1175 -600);
FORCEPROP 1 LAST VOLTAGE 4V
J 0
(-1175 -650);
DISPLAY 0.617021 (-1175 -650);
PAINT SKYBLUE (-1175 -650);
FORCEPROP 1 LAST MATERIAL X5R
J 0
(-1175 -750);
DISPLAY 0.617021 (-1175 -750);
PAINT SKYBLUE (-1175 -750);
FORCEPROP 2 LAST CDS_LOCATION C5G2
J 0
(-1175 -550);
DISPLAY 0.617021 (-1175 -550);
PAINT AQUA (-1175 -550);
DISPLAY INVISIBLE (-1175 -550);
FORCEPROP 1 LAST PATH I301
J 0
(-1175 -500);
DISPLAY 0.978723 (-1175 -500);
PAINT WHITE (-1175 -500);
DISPLAY INVISIBLE (-1175 -500);
FORCEPROP 2 LAST CDS_LIB dev_discrete
J 0
(-1225 -650);
PAINT ORANGE (-1225 -650);
DISPLAY INVISIBLE (-1225 -650);
FORCEPROP 2 LAST SEC 1
J 0
(-1175 -450);
DISPLAY 0.680851 (-1175 -450);
PAINT MONO (-1175 -450);
DISPLAY INVISIBLE (-1175 -450);
FORCEPROP 2 LAST SEC_TYPE 0603V
J 0
(-1175 -450);
DISPLAY 1.021277 (-1175 -450);
PAINT ORANGE (-1175 -450);
DISPLAY INVISIBLE (-1175 -450);
FORCEPROP 2 LAST CDS_SEC 1
J 0
(-1175 -500);
PAINT ORANGE (-1175 -500);
DISPLAY INVISIBLE (-1175 -500);
FORCEADD CAP_A..1
(-950 -650);
FORCEPROP 0 LAST BOM_SS E15431-004
J 0
(-950 -1050);
DISPLAY 0.510638 (-950 -1050);
PAINT BROWN (-950 -1050);
DISPLAY BOTH (-950 -1050);
FORCEPROP 1 LAST PART_NUMBER 602433-106
J 0
(-900 -800);
DISPLAY 0.617021 (-900 -800);
PAINT BLUE (-900 -800);
FORCEPROP 1 LAST MATERIAL X5R
J 0
(-900 -750);
DISPLAY 0.617021 (-900 -750);
PAINT SKYBLUE (-900 -750);
FORCEPROP 1 LAST TOLERANCE 20%
J 0
(-900 -700);
DISPLAY 0.617021 (-900 -700);
PAINT SKYBLUE (-900 -700);
FORCEPROP 1 LAST VALUE 47UF
J 0
(-900 -600);
DISPLAY 0.617021 (-900 -600);
PAINT SKYBLUE (-900 -600);
FORCEPROP 1 LAST LOCATION C5G4
J 0
(-900 -550);
DISPLAY 0.617021 (-900 -550);
PAINT AQUA (-900 -550);
FORCEPROP 0 LAST GROUP PWR_MLCC_CAP
J 0
(-894 -938);
DISPLAY 0.638298 (-894 -938);
PAINT BROWN (-894 -938);
DISPLAY BOTH (-894 -938);
FORCEPROP 1 LAST PACK_TYPE 0603V
J 0
(-900 -850);
DISPLAY 0.617021 (-900 -850);
PAINT SKYBLUE (-900 -850);
FORCEPROP 1 LASTPIN (-950 -550) $PN 1
J 0
(-940 -570);
DISPLAY 0.617021 (-940 -570);
PAINT ORANGE (-940 -570);
FORCEPROP 1 LAST VOLTAGE 4V
J 0
(-900 -650);
DISPLAY 0.617021 (-900 -650);
PAINT SKYBLUE (-900 -650);
FORCEPROP 1 LASTPIN (-950 -750) $PN 2
J 0
(-940 -770);
DISPLAY 0.617021 (-940 -770);
PAINT ORANGE (-940 -770);
FORCEPROP 2 LAST CDS_LOCATION C5G4
J 0
(-900 -550);
DISPLAY 0.617021 (-900 -550);
PAINT AQUA (-900 -550);
DISPLAY INVISIBLE (-900 -550);
FORCEPROP 1 LAST PATH I302
J 0
(-900 -500);
DISPLAY 0.978723 (-900 -500);
PAINT WHITE (-900 -500);
DISPLAY INVISIBLE (-900 -500);
FORCEPROP 2 LAST CDS_SEC 1
J 0
(-900 -500);
PAINT ORANGE (-900 -500);
DISPLAY INVISIBLE (-900 -500);
FORCEPROP 2 LAST SEC_TYPE 0603V
J 0
(-900 -450);
DISPLAY 1.021277 (-900 -450);
PAINT ORANGE (-900 -450);
DISPLAY INVISIBLE (-900 -450);
FORCEPROP 2 LAST SEC 1
J 0
(-900 -450);
DISPLAY 0.680851 (-900 -450);
PAINT MONO (-900 -450);
DISPLAY INVISIBLE (-900 -450);
FORCEPROP 2 LAST CDS_LIB dev_discrete
J 0
(-950 -650);
PAINT ORANGE (-950 -650);
DISPLAY INVISIBLE (-950 -650);
FORCEADD CAP_A..1
(-675 -650);
FORCEPROP 0 LAST BOM_SS E15431-004
J 0
(-675 -1000);
DISPLAY 0.510638 (-675 -1000);
PAINT BROWN (-675 -1000);
DISPLAY BOTH (-675 -1000);
FORCEPROP 1 LAST PART_NUMBER 602433-106
J 0
(-625 -800);
DISPLAY 0.617021 (-625 -800);
PAINT BLUE (-625 -800);
FORCEPROP 0 LAST GROUP PWR_MLCC_CAP
J 0
(-619 -888);
DISPLAY 0.638298 (-619 -888);
PAINT BROWN (-619 -888);
DISPLAY BOTH (-619 -888);
FORCEPROP 1 LAST PACK_TYPE 0603V
J 0
(-625 -850);
DISPLAY 0.617021 (-625 -850);
PAINT SKYBLUE (-625 -850);
FORCEPROP 1 LAST TOLERANCE 20%
J 0
(-625 -700);
DISPLAY 0.617021 (-625 -700);
PAINT SKYBLUE (-625 -700);
FORCEPROP 1 LAST VALUE 47UF
J 0
(-625 -600);
DISPLAY 0.617021 (-625 -600);
PAINT SKYBLUE (-625 -600);
FORCEPROP 1 LASTPIN (-675 -550) $PN 1
J 0
(-665 -570);
DISPLAY 0.617021 (-665 -570);
PAINT ORANGE (-665 -570);
FORCEPROP 1 LAST VOLTAGE 4V
J 0
(-625 -650);
DISPLAY 0.617021 (-625 -650);
PAINT SKYBLUE (-625 -650);
FORCEPROP 1 LASTPIN (-675 -750) $PN 2
J 0
(-665 -770);
DISPLAY 0.617021 (-665 -770);
PAINT ORANGE (-665 -770);
FORCEPROP 1 LAST LOCATION C5G13
J 0
(-625 -550);
DISPLAY 0.617021 (-625 -550);
PAINT AQUA (-625 -550);
FORCEPROP 1 LAST MATERIAL X5R
J 0
(-625 -750);
DISPLAY 0.617021 (-625 -750);
PAINT SKYBLUE (-625 -750);
FORCEPROP 2 LAST CDS_LOCATION C5G13
J 0
(-625 -550);
DISPLAY 0.617021 (-625 -550);
PAINT AQUA (-625 -550);
DISPLAY INVISIBLE (-625 -550);
FORCEPROP 1 LAST PATH I303
J 0
(-625 -500);
DISPLAY 0.978723 (-625 -500);
PAINT WHITE (-625 -500);
DISPLAY INVISIBLE (-625 -500);
FORCEPROP 2 LAST CDS_LIB dev_discrete
J 0
(-675 -650);
PAINT ORANGE (-675 -650);
DISPLAY INVISIBLE (-675 -650);
FORCEPROP 2 LAST SEC 1
J 0
(-625 -450);
DISPLAY 0.680851 (-625 -450);
PAINT MONO (-625 -450);
DISPLAY INVISIBLE (-625 -450);
FORCEPROP 2 LAST SEC_TYPE 0603V
J 0
(-625 -450);
DISPLAY 1.021277 (-625 -450);
PAINT ORANGE (-625 -450);
DISPLAY INVISIBLE (-625 -450);
FORCEPROP 2 LAST CDS_SEC 1
J 0
(-625 -500);
PAINT ORANGE (-625 -500);
DISPLAY INVISIBLE (-625 -500);
FORCEADD CAP_A..1
(-375 -650);
FORCEPROP 0 LAST BOM_SS E15431-004
J 0
(-375 -1050);
DISPLAY 0.510638 (-375 -1050);
PAINT BROWN (-375 -1050);
DISPLAY BOTH (-375 -1050);
FORCEPROP 1 LASTPIN (-375 -750) $PN 2
J 0
(-365 -770);
DISPLAY 0.617021 (-365 -770);
PAINT ORANGE (-365 -770);
FORCEPROP 1 LAST MATERIAL X5R
J 0
(-325 -750);
DISPLAY 0.617021 (-325 -750);
PAINT SKYBLUE (-325 -750);
FORCEPROP 1 LAST TOLERANCE 20%
J 0
(-325 -700);
DISPLAY 0.617021 (-325 -700);
PAINT SKYBLUE (-325 -700);
FORCEPROP 1 LAST PART_NUMBER 602433-106
J 0
(-325 -800);
DISPLAY 0.617021 (-325 -800);
PAINT BLUE (-325 -800);
FORCEPROP 0 LAST GROUP PWR_MLCC_CAP
J 0
(-319 -938);
DISPLAY 0.638298 (-319 -938);
PAINT BROWN (-319 -938);
DISPLAY BOTH (-319 -938);
FORCEPROP 1 LAST LOCATION C5G6
J 0
(-325 -550);
DISPLAY 0.617021 (-325 -550);
PAINT AQUA (-325 -550);
FORCEPROP 1 LAST VALUE 47UF
J 0
(-325 -600);
DISPLAY 0.617021 (-325 -600);
PAINT SKYBLUE (-325 -600);
FORCEPROP 1 LAST PACK_TYPE 0603V
J 0
(-325 -850);
DISPLAY 0.617021 (-325 -850);
PAINT SKYBLUE (-325 -850);
FORCEPROP 1 LASTPIN (-375 -550) $PN 1
J 0
(-365 -570);
DISPLAY 0.617021 (-365 -570);
PAINT ORANGE (-365 -570);
FORCEPROP 1 LAST VOLTAGE 4V
J 0
(-325 -650);
DISPLAY 0.617021 (-325 -650);
PAINT SKYBLUE (-325 -650);
FORCEPROP 2 LAST CDS_LOCATION C5G6
J 0
(-325 -550);
DISPLAY 0.617021 (-325 -550);
PAINT AQUA (-325 -550);
DISPLAY INVISIBLE (-325 -550);
FORCEPROP 1 LAST PATH I304
J 0
(-325 -500);
DISPLAY 0.978723 (-325 -500);
PAINT WHITE (-325 -500);
DISPLAY INVISIBLE (-325 -500);
FORCEPROP 2 LAST CDS_SEC 1
J 0
(-325 -500);
PAINT ORANGE (-325 -500);
DISPLAY INVISIBLE (-325 -500);
FORCEPROP 2 LAST SEC_TYPE 0603V
J 0
(-325 -450);
DISPLAY 1.021277 (-325 -450);
PAINT ORANGE (-325 -450);
DISPLAY INVISIBLE (-325 -450);
FORCEPROP 2 LAST SEC 1
J 0
(-325 -450);
DISPLAY 0.680851 (-325 -450);
PAINT MONO (-325 -450);
DISPLAY INVISIBLE (-325 -450);
FORCEPROP 2 LAST CDS_LIB dev_discrete
J 0
(-375 -650);
PAINT ORANGE (-375 -650);
DISPLAY INVISIBLE (-375 -650);
FORCEADD CAP_A..1
(-75 -650);
FORCEPROP 0 LAST BOM_SS E15431-004
J 0
(-75 -1000);
DISPLAY 0.510638 (-75 -1000);
PAINT BROWN (-75 -1000);
DISPLAY BOTH (-75 -1000);
FORCEPROP 1 LAST LOCATION C5G5
J 0
(-25 -550);
DISPLAY 0.617021 (-25 -550);
PAINT AQUA (-25 -550);
FORCEPROP 1 LAST PART_NUMBER 602433-106
J 0
(-25 -800);
DISPLAY 0.617021 (-25 -800);
PAINT BLUE (-25 -800);
FORCEPROP 1 LAST VALUE 47UF
J 0
(-25 -600);
DISPLAY 0.617021 (-25 -600);
PAINT SKYBLUE (-25 -600);
FORCEPROP 0 LAST GROUP PWR_MLCC_CAP
J 0
(-19 -888);
DISPLAY 0.638298 (-19 -888);
PAINT BROWN (-19 -888);
DISPLAY BOTH (-19 -888);
FORCEPROP 1 LAST PACK_TYPE 0603V
J 0
(-25 -850);
DISPLAY 0.617021 (-25 -850);
PAINT SKYBLUE (-25 -850);
FORCEPROP 1 LAST VOLTAGE 4V
J 0
(-25 -650);
DISPLAY 0.617021 (-25 -650);
PAINT SKYBLUE (-25 -650);
FORCEPROP 1 LAST TOLERANCE 20%
J 0
(-25 -700);
DISPLAY 0.617021 (-25 -700);
PAINT SKYBLUE (-25 -700);
FORCEPROP 1 LASTPIN (-75 -750) $PN 2
J 0
(-65 -770);
DISPLAY 0.617021 (-65 -770);
PAINT ORANGE (-65 -770);
FORCEPROP 1 LASTPIN (-75 -550) $PN 1
J 0
(-65 -570);
DISPLAY 0.617021 (-65 -570);
PAINT ORANGE (-65 -570);
FORCEPROP 1 LAST MATERIAL X5R
J 0
(-25 -750);
DISPLAY 0.617021 (-25 -750);
PAINT SKYBLUE (-25 -750);
FORCEPROP 2 LAST CDS_LOCATION C5G5
J 0
(-25 -550);
DISPLAY 0.617021 (-25 -550);
PAINT AQUA (-25 -550);
DISPLAY INVISIBLE (-25 -550);
FORCEPROP 1 LAST PATH I305
J 0
(-25 -500);
DISPLAY 0.978723 (-25 -500);
PAINT WHITE (-25 -500);
DISPLAY INVISIBLE (-25 -500);
FORCEPROP 2 LAST CDS_LIB dev_discrete
J 0
(-75 -650);
PAINT ORANGE (-75 -650);
DISPLAY INVISIBLE (-75 -650);
FORCEPROP 2 LAST SEC 1
J 0
(-25 -450);
DISPLAY 0.680851 (-25 -450);
PAINT MONO (-25 -450);
DISPLAY INVISIBLE (-25 -450);
FORCEPROP 2 LAST SEC_TYPE 0603V
J 0
(-25 -450);
DISPLAY 1.021277 (-25 -450);
PAINT ORANGE (-25 -450);
DISPLAY INVISIBLE (-25 -450);
FORCEPROP 2 LAST CDS_SEC 1
J 0
(-25 -500);
PAINT ORANGE (-25 -500);
DISPLAY INVISIBLE (-25 -500);
FORCEADD CAP_A..1
(200 -650);
FORCEPROP 0 LAST BOM_SS E15431-004
J 0
(200 -1050);
DISPLAY 0.510638 (200 -1050);
PAINT BROWN (200 -1050);
DISPLAY BOTH (200 -1050);
FORCEPROP 0 LAST GROUP PWR_MLCC_CAP
J 0
(256 -938);
DISPLAY 0.638298 (256 -938);
PAINT BROWN (256 -938);
DISPLAY BOTH (256 -938);
FORCEPROP 1 LAST VALUE 47UF
J 0
(250 -600);
DISPLAY 0.617021 (250 -600);
PAINT SKYBLUE (250 -600);
FORCEPROP 1 LAST TOLERANCE 20%
J 0
(250 -700);
DISPLAY 0.617021 (250 -700);
PAINT SKYBLUE (250 -700);
FORCEPROP 1 LAST VOLTAGE 4V
J 0
(250 -650);
DISPLAY 0.617021 (250 -650);
PAINT SKYBLUE (250 -650);
FORCEPROP 1 LAST PACK_TYPE 0603V
J 0
(250 -850);
DISPLAY 0.617021 (250 -850);
PAINT SKYBLUE (250 -850);
FORCEPROP 1 LAST MATERIAL X5R
J 0
(250 -750);
DISPLAY 0.617021 (250 -750);
PAINT SKYBLUE (250 -750);
FORCEPROP 1 LAST LOCATION C5G7
J 0
(250 -550);
DISPLAY 0.617021 (250 -550);
PAINT AQUA (250 -550);
FORCEPROP 1 LASTPIN (200 -550) $PN 1
J 0
(210 -570);
DISPLAY 0.617021 (210 -570);
PAINT ORANGE (210 -570);
FORCEPROP 1 LASTPIN (200 -750) $PN 2
J 0
(210 -770);
DISPLAY 0.617021 (210 -770);
PAINT ORANGE (210 -770);
FORCEPROP 1 LAST PART_NUMBER 602433-106
J 0
(250 -800);
DISPLAY 0.617021 (250 -800);
PAINT BLUE (250 -800);
FORCEPROP 2 LAST CDS_LOCATION C5G7
J 0
(250 -550);
DISPLAY 0.617021 (250 -550);
PAINT AQUA (250 -550);
DISPLAY INVISIBLE (250 -550);
FORCEPROP 1 LAST PATH I306
J 0
(250 -500);
DISPLAY 0.978723 (250 -500);
PAINT WHITE (250 -500);
DISPLAY INVISIBLE (250 -500);
FORCEPROP 2 LAST CDS_SEC 1
J 0
(250 -500);
PAINT ORANGE (250 -500);
DISPLAY INVISIBLE (250 -500);
FORCEPROP 2 LAST SEC_TYPE 0603V
J 0
(250 -450);
DISPLAY 1.021277 (250 -450);
PAINT ORANGE (250 -450);
DISPLAY INVISIBLE (250 -450);
FORCEPROP 2 LAST SEC 1
J 0
(250 -450);
DISPLAY 0.680851 (250 -450);
PAINT MONO (250 -450);
DISPLAY INVISIBLE (250 -450);
FORCEPROP 2 LAST CDS_LIB dev_discrete
J 0
(200 -650);
PAINT ORANGE (200 -650);
DISPLAY INVISIBLE (200 -650);
FORCEADD CAP_A..1
(525 -650);
FORCEPROP 0 LAST BOM_SS E15431-004
J 0
(525 -1000);
DISPLAY 0.510638 (525 -1000);
PAINT BROWN (525 -1000);
DISPLAY BOTH (525 -1000);
FORCEPROP 0 LAST GROUP PWR_MLCC_CAP
J 0
(581 -888);
DISPLAY 0.638298 (581 -888);
PAINT BROWN (581 -888);
DISPLAY BOTH (581 -888);
FORCEPROP 1 LAST LOCATION C5G1
J 0
(575 -550);
DISPLAY 0.617021 (575 -550);
PAINT AQUA (575 -550);
FORCEPROP 1 LASTPIN (525 -550) $PN 1
J 0
(535 -570);
DISPLAY 0.617021 (535 -570);
PAINT ORANGE (535 -570);
FORCEPROP 1 LAST PACK_TYPE 0603V
J 0
(575 -850);
DISPLAY 0.617021 (575 -850);
PAINT SKYBLUE (575 -850);
FORCEPROP 1 LASTPIN (525 -750) $PN 2
J 0
(535 -770);
DISPLAY 0.617021 (535 -770);
PAINT ORANGE (535 -770);
FORCEPROP 1 LAST MATERIAL X5R
J 0
(575 -750);
DISPLAY 0.617021 (575 -750);
PAINT SKYBLUE (575 -750);
FORCEPROP 1 LAST PART_NUMBER 602433-106
J 0
(575 -800);
DISPLAY 0.617021 (575 -800);
PAINT BLUE (575 -800);
FORCEPROP 1 LAST TOLERANCE 20%
J 0
(575 -700);
DISPLAY 0.617021 (575 -700);
PAINT SKYBLUE (575 -700);
FORCEPROP 1 LAST VOLTAGE 4V
J 0
(575 -650);
DISPLAY 0.617021 (575 -650);
PAINT SKYBLUE (575 -650);
FORCEPROP 1 LAST VALUE 47UF
J 0
(575 -600);
DISPLAY 0.617021 (575 -600);
PAINT SKYBLUE (575 -600);
FORCEPROP 2 LAST CDS_LOCATION C5G1
J 0
(575 -550);
DISPLAY 0.617021 (575 -550);
PAINT AQUA (575 -550);
DISPLAY INVISIBLE (575 -550);
FORCEPROP 1 LAST PATH I307
J 0
(575 -500);
DISPLAY 0.978723 (575 -500);
PAINT WHITE (575 -500);
DISPLAY INVISIBLE (575 -500);
FORCEPROP 2 LAST CDS_LIB dev_discrete
J 0
(525 -650);
PAINT ORANGE (525 -650);
DISPLAY INVISIBLE (525 -650);
FORCEPROP 2 LAST SEC 1
J 0
(575 -450);
DISPLAY 0.680851 (575 -450);
PAINT MONO (575 -450);
DISPLAY INVISIBLE (575 -450);
FORCEPROP 2 LAST SEC_TYPE 0603V
J 0
(575 -450);
DISPLAY 1.021277 (575 -450);
PAINT ORANGE (575 -450);
DISPLAY INVISIBLE (575 -450);
FORCEPROP 2 LAST CDS_SEC 1
J 0
(575 -500);
PAINT ORANGE (575 -500);
DISPLAY INVISIBLE (575 -500);
FORCEADD CAP_A..1
(825 -650);
FORCEPROP 0 LAST BOM_SS E15431-004
J 0
(825 -1050);
DISPLAY 0.510638 (825 -1050);
PAINT BROWN (825 -1050);
DISPLAY BOTH (825 -1050);
FORCEPROP 0 LAST GROUP PWR_MLCC_CAP
J 0
(881 -938);
DISPLAY 0.638298 (881 -938);
PAINT BROWN (881 -938);
DISPLAY BOTH (881 -938);
FORCEPROP 1 LAST LOCATION C5G8
J 0
(875 -550);
DISPLAY 0.617021 (875 -550);
PAINT AQUA (875 -550);
FORCEPROP 1 LAST VALUE 47UF
J 0
(875 -600);
DISPLAY 0.617021 (875 -600);
PAINT SKYBLUE (875 -600);
FORCEPROP 1 LAST PACK_TYPE 0603V
J 0
(875 -850);
DISPLAY 0.617021 (875 -850);
PAINT SKYBLUE (875 -850);
FORCEPROP 1 LASTPIN (825 -750) $PN 2
J 0
(835 -770);
DISPLAY 0.617021 (835 -770);
PAINT ORANGE (835 -770);
FORCEPROP 1 LAST MATERIAL X5R
J 0
(875 -750);
DISPLAY 0.617021 (875 -750);
PAINT SKYBLUE (875 -750);
FORCEPROP 1 LAST PART_NUMBER 602433-106
J 0
(875 -800);
DISPLAY 0.617021 (875 -800);
PAINT BLUE (875 -800);
FORCEPROP 1 LAST TOLERANCE 20%
J 0
(875 -700);
DISPLAY 0.617021 (875 -700);
PAINT SKYBLUE (875 -700);
FORCEPROP 1 LAST VOLTAGE 4V
J 0
(875 -650);
DISPLAY 0.617021 (875 -650);
PAINT SKYBLUE (875 -650);
FORCEPROP 1 LASTPIN (825 -550) $PN 1
J 0
(835 -570);
DISPLAY 0.617021 (835 -570);
PAINT ORANGE (835 -570);
FORCEPROP 2 LAST CDS_LOCATION C5G8
J 0
(875 -550);
DISPLAY 0.617021 (875 -550);
PAINT AQUA (875 -550);
DISPLAY INVISIBLE (875 -550);
FORCEPROP 1 LAST PATH I308
J 0
(875 -500);
DISPLAY 0.978723 (875 -500);
PAINT WHITE (875 -500);
DISPLAY INVISIBLE (875 -500);
FORCEPROP 2 LAST CDS_SEC 1
J 0
(875 -500);
PAINT ORANGE (875 -500);
DISPLAY INVISIBLE (875 -500);
FORCEPROP 2 LAST SEC_TYPE 0603V
J 0
(875 -450);
DISPLAY 1.021277 (875 -450);
PAINT ORANGE (875 -450);
DISPLAY INVISIBLE (875 -450);
FORCEPROP 2 LAST SEC 1
J 0
(875 -450);
DISPLAY 0.680851 (875 -450);
PAINT MONO (875 -450);
DISPLAY INVISIBLE (875 -450);
FORCEPROP 2 LAST CDS_LIB dev_discrete
J 0
(825 -650);
PAINT ORANGE (825 -650);
DISPLAY INVISIBLE (825 -650);
FORCEADD CAP_A..1
(1125 -650);
FORCEPROP 0 LAST BOM_SS E15431-004
J 0
(1125 -1000);
DISPLAY 0.510638 (1125 -1000);
PAINT BROWN (1125 -1000);
DISPLAY BOTH (1125 -1000);
FORCEPROP 1 LAST LOCATION C5G18
J 0
(1175 -550);
DISPLAY 0.617021 (1175 -550);
PAINT AQUA (1175 -550);
FORCEPROP 1 LAST VALUE 47UF
J 0
(1175 -600);
DISPLAY 0.617021 (1175 -600);
PAINT SKYBLUE (1175 -600);
FORCEPROP 1 LAST VOLTAGE 4V
J 0
(1175 -650);
DISPLAY 0.617021 (1175 -650);
PAINT SKYBLUE (1175 -650);
FORCEPROP 1 LAST TOLERANCE 20%
J 0
(1175 -700);
DISPLAY 0.617021 (1175 -700);
PAINT SKYBLUE (1175 -700);
FORCEPROP 1 LAST MATERIAL X5R
J 0
(1175 -750);
DISPLAY 0.617021 (1175 -750);
PAINT SKYBLUE (1175 -750);
FORCEPROP 1 LAST PART_NUMBER 602433-106
J 0
(1175 -800);
DISPLAY 0.617021 (1175 -800);
PAINT BLUE (1175 -800);
FORCEPROP 1 LAST PACK_TYPE 0603V
J 0
(1175 -850);
DISPLAY 0.617021 (1175 -850);
PAINT SKYBLUE (1175 -850);
FORCEPROP 0 LAST GROUP PWR_MLCC_CAP
J 0
(1181 -888);
DISPLAY 0.638298 (1181 -888);
PAINT BROWN (1181 -888);
DISPLAY BOTH (1181 -888);
FORCEPROP 1 LASTPIN (1125 -550) $PN 1
J 0
(1135 -570);
DISPLAY 0.617021 (1135 -570);
PAINT ORANGE (1135 -570);
FORCEPROP 1 LASTPIN (1125 -750) $PN 2
J 0
(1135 -770);
DISPLAY 0.617021 (1135 -770);
PAINT ORANGE (1135 -770);
FORCEPROP 2 LAST CDS_LOCATION C5G18
J 0
(1175 -550);
DISPLAY 0.617021 (1175 -550);
PAINT AQUA (1175 -550);
DISPLAY INVISIBLE (1175 -550);
FORCEPROP 1 LAST PATH I309
J 0
(1175 -500);
DISPLAY 0.978723 (1175 -500);
PAINT WHITE (1175 -500);
DISPLAY INVISIBLE (1175 -500);
FORCEPROP 2 LAST CDS_LIB dev_discrete
J 0
(1125 -650);
PAINT ORANGE (1125 -650);
DISPLAY INVISIBLE (1125 -650);
FORCEPROP 2 LAST SEC 1
J 0
(1175 -450);
DISPLAY 0.680851 (1175 -450);
PAINT MONO (1175 -450);
DISPLAY INVISIBLE (1175 -450);
FORCEPROP 2 LAST SEC_TYPE 0603V
J 0
(1175 -450);
DISPLAY 1.021277 (1175 -450);
PAINT ORANGE (1175 -450);
DISPLAY INVISIBLE (1175 -450);
FORCEPROP 2 LAST CDS_SEC 1
J 0
(1175 -500);
PAINT ORANGE (1175 -500);
DISPLAY INVISIBLE (1175 -500);
FORCEADD CAP_A..1
(1400 -650);
FORCEPROP 0 LAST BOM_SS E15431-004
J 0
(1400 -1050);
DISPLAY 0.510638 (1400 -1050);
PAINT BROWN (1400 -1050);
DISPLAY BOTH (1400 -1050);
FORCEPROP 0 LAST GROUP PWR_MLCC_CAP
J 0
(1456 -938);
DISPLAY 0.638298 (1456 -938);
PAINT BROWN (1456 -938);
DISPLAY BOTH (1456 -938);
FORCEPROP 1 LAST MATERIAL X5R
J 0
(1450 -750);
DISPLAY 0.617021 (1450 -750);
PAINT SKYBLUE (1450 -750);
FORCEPROP 1 LAST TOLERANCE 20%
J 0
(1450 -700);
DISPLAY 0.617021 (1450 -700);
PAINT SKYBLUE (1450 -700);
FORCEPROP 1 LAST LOCATION C5G17
J 0
(1450 -550);
DISPLAY 0.617021 (1450 -550);
PAINT AQUA (1450 -550);
FORCEPROP 1 LAST PACK_TYPE 0603V
J 0
(1450 -850);
DISPLAY 0.617021 (1450 -850);
PAINT SKYBLUE (1450 -850);
FORCEPROP 1 LASTPIN (1400 -550) $PN 1
J 0
(1410 -570);
DISPLAY 0.617021 (1410 -570);
PAINT ORANGE (1410 -570);
FORCEPROP 1 LASTPIN (1400 -750) $PN 2
J 0
(1410 -770);
DISPLAY 0.617021 (1410 -770);
PAINT ORANGE (1410 -770);
FORCEPROP 1 LAST PART_NUMBER 602433-106
J 0
(1450 -800);
DISPLAY 0.617021 (1450 -800);
PAINT BLUE (1450 -800);
FORCEPROP 1 LAST VALUE 47UF
J 0
(1450 -600);
DISPLAY 0.617021 (1450 -600);
PAINT SKYBLUE (1450 -600);
FORCEPROP 1 LAST VOLTAGE 4V
J 0
(1450 -650);
DISPLAY 0.617021 (1450 -650);
PAINT SKYBLUE (1450 -650);
FORCEPROP 2 LAST CDS_LOCATION C5G17
J 0
(1450 -550);
DISPLAY 0.617021 (1450 -550);
PAINT AQUA (1450 -550);
DISPLAY INVISIBLE (1450 -550);
FORCEPROP 1 LAST PATH I310
J 0
(1450 -500);
DISPLAY 0.978723 (1450 -500);
PAINT WHITE (1450 -500);
DISPLAY INVISIBLE (1450 -500);
FORCEPROP 2 LAST CDS_SEC 1
J 0
(1450 -500);
PAINT ORANGE (1450 -500);
DISPLAY INVISIBLE (1450 -500);
FORCEPROP 2 LAST SEC_TYPE 0603V
J 0
(1450 -450);
DISPLAY 1.021277 (1450 -450);
PAINT ORANGE (1450 -450);
DISPLAY INVISIBLE (1450 -450);
FORCEPROP 2 LAST SEC 1
J 0
(1450 -450);
DISPLAY 0.680851 (1450 -450);
PAINT MONO (1450 -450);
DISPLAY INVISIBLE (1450 -450);
FORCEPROP 2 LAST CDS_LIB dev_discrete
J 0
(1400 -650);
PAINT ORANGE (1400 -650);
DISPLAY INVISIBLE (1400 -650);
FORCEADD CAP_A..1
(1675 -650);
FORCEPROP 0 LAST BOM_SS E15431-004
J 0
(1675 -1000);
DISPLAY 0.510638 (1675 -1000);
PAINT BROWN (1675 -1000);
DISPLAY BOTH (1675 -1000);
FORCEPROP 1 LAST PART_NUMBER 602433-106
J 0
(1725 -800);
DISPLAY 0.617021 (1725 -800);
PAINT BLUE (1725 -800);
FORCEPROP 0 LAST GROUP PWR_MLCC_CAP
J 0
(1731 -888);
DISPLAY 0.638298 (1731 -888);
PAINT BROWN (1731 -888);
DISPLAY BOTH (1731 -888);
FORCEPROP 1 LAST TOLERANCE 20%
J 0
(1725 -700);
DISPLAY 0.617021 (1725 -700);
PAINT SKYBLUE (1725 -700);
FORCEPROP 1 LAST MATERIAL X5R
J 0
(1725 -750);
DISPLAY 0.617021 (1725 -750);
PAINT SKYBLUE (1725 -750);
FORCEPROP 1 LASTPIN (1675 -750) $PN 2
J 0
(1685 -770);
DISPLAY 0.617021 (1685 -770);
PAINT ORANGE (1685 -770);
FORCEPROP 1 LASTPIN (1675 -550) $PN 1
J 0
(1685 -570);
DISPLAY 0.617021 (1685 -570);
PAINT ORANGE (1685 -570);
FORCEPROP 1 LAST PACK_TYPE 0603V
J 0
(1725 -850);
DISPLAY 0.617021 (1725 -850);
PAINT SKYBLUE (1725 -850);
FORCEPROP 1 LAST VOLTAGE 4V
J 0
(1725 -650);
DISPLAY 0.617021 (1725 -650);
PAINT SKYBLUE (1725 -650);
FORCEPROP 1 LAST VALUE 47UF
J 0
(1725 -600);
DISPLAY 0.617021 (1725 -600);
PAINT SKYBLUE (1725 -600);
FORCEPROP 1 LAST LOCATION C5G14
J 0
(1725 -550);
DISPLAY 0.617021 (1725 -550);
PAINT AQUA (1725 -550);
FORCEPROP 2 LAST CDS_LOCATION C5G14
J 0
(1725 -550);
DISPLAY 0.617021 (1725 -550);
PAINT AQUA (1725 -550);
DISPLAY INVISIBLE (1725 -550);
FORCEPROP 1 LAST PATH I311
J 0
(1725 -500);
DISPLAY 0.978723 (1725 -500);
PAINT WHITE (1725 -500);
DISPLAY INVISIBLE (1725 -500);
FORCEPROP 2 LAST CDS_LIB dev_discrete
J 0
(1675 -650);
PAINT ORANGE (1675 -650);
DISPLAY INVISIBLE (1675 -650);
FORCEPROP 2 LAST SEC 1
J 0
(1725 -450);
DISPLAY 0.680851 (1725 -450);
PAINT MONO (1725 -450);
DISPLAY INVISIBLE (1725 -450);
FORCEPROP 2 LAST SEC_TYPE 0603V
J 0
(1725 -450);
DISPLAY 1.021277 (1725 -450);
PAINT ORANGE (1725 -450);
DISPLAY INVISIBLE (1725 -450);
FORCEPROP 2 LAST CDS_SEC 1
J 0
(1725 -500);
PAINT ORANGE (1725 -500);
DISPLAY INVISIBLE (1725 -500);
FORCEADD CAP_A..1
(1975 -650);
FORCEPROP 0 LAST BOM_SS E15431-004
J 0
(1975 -1050);
DISPLAY 0.510638 (1975 -1050);
PAINT BROWN (1975 -1050);
DISPLAY BOTH (1975 -1050);
FORCEPROP 0 LAST GROUP PWR_MLCC_CAP
J 0
(2006 -938);
DISPLAY 0.638298 (2006 -938);
PAINT BROWN (2006 -938);
DISPLAY BOTH (2006 -938);
FORCEPROP 1 LAST VOLTAGE 4V
J 0
(2025 -650);
DISPLAY 0.617021 (2025 -650);
PAINT SKYBLUE (2025 -650);
FORCEPROP 1 LASTPIN (1975 -750) $PN 2
J 0
(1985 -770);
DISPLAY 0.617021 (1985 -770);
PAINT ORANGE (1985 -770);
FORCEPROP 1 LAST PACK_TYPE 0603V
J 0
(2025 -850);
DISPLAY 0.617021 (2025 -850);
PAINT SKYBLUE (2025 -850);
FORCEPROP 1 LASTPIN (1975 -550) $PN 1
J 0
(1985 -570);
DISPLAY 0.617021 (1985 -570);
PAINT ORANGE (1985 -570);
FORCEPROP 1 LAST MATERIAL X5R
J 0
(2025 -750);
DISPLAY 0.617021 (2025 -750);
PAINT SKYBLUE (2025 -750);
FORCEPROP 1 LAST TOLERANCE 20%
J 0
(2025 -700);
DISPLAY 0.617021 (2025 -700);
PAINT SKYBLUE (2025 -700);
FORCEPROP 1 LAST PART_NUMBER 602433-106
J 0
(2025 -800);
DISPLAY 0.617021 (2025 -800);
PAINT BLUE (2025 -800);
FORCEPROP 1 LAST VALUE 47UF
J 0
(2025 -600);
DISPLAY 0.617021 (2025 -600);
PAINT SKYBLUE (2025 -600);
FORCEPROP 1 LAST LOCATION C5G16
J 0
(2025 -550);
DISPLAY 0.617021 (2025 -550);
PAINT AQUA (2025 -550);
FORCEPROP 2 LAST CDS_LOCATION C5G16
J 0
(2025 -550);
DISPLAY 0.617021 (2025 -550);
PAINT AQUA (2025 -550);
DISPLAY INVISIBLE (2025 -550);
FORCEPROP 1 LAST PATH I312
J 0
(2025 -500);
DISPLAY 0.978723 (2025 -500);
PAINT WHITE (2025 -500);
DISPLAY INVISIBLE (2025 -500);
FORCEPROP 2 LAST CDS_SEC 1
J 0
(2025 -500);
PAINT ORANGE (2025 -500);
DISPLAY INVISIBLE (2025 -500);
FORCEPROP 2 LAST SEC_TYPE 0603V
J 0
(2025 -450);
DISPLAY 1.021277 (2025 -450);
PAINT ORANGE (2025 -450);
DISPLAY INVISIBLE (2025 -450);
FORCEPROP 2 LAST SEC 1
J 0
(2025 -450);
DISPLAY 0.680851 (2025 -450);
PAINT MONO (2025 -450);
DISPLAY INVISIBLE (2025 -450);
FORCEPROP 2 LAST CDS_LIB dev_discrete
J 0
(1975 -650);
PAINT ORANGE (1975 -650);
DISPLAY INVISIBLE (1975 -650);
FORCEADD CAP_A..1
(2275 -650);
FORCEPROP 0 LAST BOM_SS E15431-004
J 0
(2275 -1000);
DISPLAY 0.510638 (2275 -1000);
PAINT BROWN (2275 -1000);
DISPLAY BOTH (2275 -1000);
FORCEPROP 0 LAST GROUP PWR_MLCC_CAP
J 0
(2331 -888);
DISPLAY 0.638298 (2331 -888);
PAINT BROWN (2331 -888);
DISPLAY BOTH (2331 -888);
FORCEPROP 1 LASTPIN (2275 -750) $PN 2
J 0
(2285 -770);
DISPLAY 0.617021 (2285 -770);
PAINT ORANGE (2285 -770);
FORCEPROP 1 LASTPIN (2275 -550) $PN 1
J 0
(2285 -570);
DISPLAY 0.617021 (2285 -570);
PAINT ORANGE (2285 -570);
FORCEPROP 1 LAST LOCATION C5G15
J 0
(2325 -550);
DISPLAY 0.617021 (2325 -550);
PAINT AQUA (2325 -550);
FORCEPROP 1 LAST VALUE 47UF
J 0
(2325 -600);
DISPLAY 0.617021 (2325 -600);
PAINT SKYBLUE (2325 -600);
FORCEPROP 1 LAST VOLTAGE 4V
J 0
(2325 -650);
DISPLAY 0.617021 (2325 -650);
PAINT SKYBLUE (2325 -650);
FORCEPROP 1 LAST TOLERANCE 20%
J 0
(2325 -700);
DISPLAY 0.617021 (2325 -700);
PAINT SKYBLUE (2325 -700);
FORCEPROP 1 LAST MATERIAL X5R
J 0
(2325 -750);
DISPLAY 0.617021 (2325 -750);
PAINT SKYBLUE (2325 -750);
FORCEPROP 1 LAST PART_NUMBER 602433-106
J 0
(2325 -800);
DISPLAY 0.617021 (2325 -800);
PAINT BLUE (2325 -800);
FORCEPROP 1 LAST PACK_TYPE 0603V
J 0
(2325 -850);
DISPLAY 0.617021 (2325 -850);
PAINT SKYBLUE (2325 -850);
FORCEPROP 2 LAST CDS_LOCATION C5G15
J 0
(2325 -550);
DISPLAY 0.617021 (2325 -550);
PAINT AQUA (2325 -550);
DISPLAY INVISIBLE (2325 -550);
FORCEPROP 1 LAST PATH I313
J 0
(2325 -500);
DISPLAY 0.978723 (2325 -500);
PAINT WHITE (2325 -500);
DISPLAY INVISIBLE (2325 -500);
FORCEPROP 2 LAST CDS_LIB dev_discrete
J 0
(2275 -650);
PAINT ORANGE (2275 -650);
DISPLAY INVISIBLE (2275 -650);
FORCEPROP 2 LAST SEC 1
J 0
(2325 -450);
DISPLAY 0.680851 (2325 -450);
PAINT MONO (2325 -450);
DISPLAY INVISIBLE (2325 -450);
FORCEPROP 2 LAST SEC_TYPE 0603V
J 0
(2325 -450);
DISPLAY 1.021277 (2325 -450);
PAINT ORANGE (2325 -450);
DISPLAY INVISIBLE (2325 -450);
FORCEPROP 2 LAST CDS_SEC 1
J 0
(2325 -500);
PAINT ORANGE (2325 -500);
DISPLAY INVISIBLE (2325 -500);
FORCEADD CAP_A..1
(2550 -650);
FORCEPROP 0 LAST BOM_SS E15431-004
J 0
(2550 -1050);
DISPLAY 0.510638 (2550 -1050);
PAINT BROWN (2550 -1050);
DISPLAY BOTH (2550 -1050);
FORCEPROP 0 LAST GROUP PWR_MLCC_CAP
J 0
(2606 -938);
DISPLAY 0.638298 (2606 -938);
PAINT BROWN (2606 -938);
DISPLAY BOTH (2606 -938);
FORCEPROP 1 LAST TOLERANCE 20%
J 0
(2600 -700);
DISPLAY 0.617021 (2600 -700);
PAINT SKYBLUE (2600 -700);
FORCEPROP 1 LASTPIN (2550 -550) $PN 1
J 0
(2560 -570);
DISPLAY 0.617021 (2560 -570);
PAINT ORANGE (2560 -570);
FORCEPROP 1 LAST PACK_TYPE 0603V
J 0
(2600 -850);
DISPLAY 0.617021 (2600 -850);
PAINT SKYBLUE (2600 -850);
FORCEPROP 1 LAST VALUE 47UF
J 0
(2600 -600);
DISPLAY 0.617021 (2600 -600);
PAINT SKYBLUE (2600 -600);
FORCEPROP 1 LAST VOLTAGE 4V
J 0
(2600 -650);
DISPLAY 0.617021 (2600 -650);
PAINT SKYBLUE (2600 -650);
FORCEPROP 1 LAST LOCATION C5G3
J 0
(2600 -550);
DISPLAY 0.617021 (2600 -550);
PAINT AQUA (2600 -550);
FORCEPROP 1 LASTPIN (2550 -750) $PN 2
J 0
(2560 -770);
DISPLAY 0.617021 (2560 -770);
PAINT ORANGE (2560 -770);
FORCEPROP 1 LAST MATERIAL X5R
J 0
(2600 -750);
DISPLAY 0.617021 (2600 -750);
PAINT SKYBLUE (2600 -750);
FORCEPROP 1 LAST PART_NUMBER 602433-106
J 0
(2600 -800);
DISPLAY 0.617021 (2600 -800);
PAINT BLUE (2600 -800);
FORCEPROP 2 LAST CDS_LOCATION C5G3
J 0
(2600 -550);
DISPLAY 0.617021 (2600 -550);
PAINT AQUA (2600 -550);
DISPLAY INVISIBLE (2600 -550);
FORCEPROP 2 LAST CDS_LIB dev_discrete
J 0
(2550 -650);
PAINT ORANGE (2550 -650);
DISPLAY INVISIBLE (2550 -650);
FORCEPROP 2 LAST SEC 1
J 0
(2600 -450);
DISPLAY 0.680851 (2600 -450);
PAINT MONO (2600 -450);
DISPLAY INVISIBLE (2600 -450);
FORCEPROP 2 LAST SEC_TYPE 0603V
J 0
(2600 -450);
DISPLAY 1.021277 (2600 -450);
PAINT ORANGE (2600 -450);
DISPLAY INVISIBLE (2600 -450);
FORCEPROP 2 LAST CDS_SEC 1
J 0
(2600 -500);
PAINT ORANGE (2600 -500);
DISPLAY INVISIBLE (2600 -500);
FORCEPROP 1 LAST PATH I314
J 0
(2600 -500);
DISPLAY 0.978723 (2600 -500);
PAINT WHITE (2600 -500);
DISPLAY INVISIBLE (2600 -500);
FORCEADD CAP..1
(4725 2850);
FORCEPROP 1 LAST PACK_TYPE 0805
J 0
(4775 2700);
DISPLAY 0.617021 (4775 2700);
PAINT SKYBLUE (4775 2700);
FORCEPROP 1 LAST LOCATION C5U1
J 0
(4775 2950);
DISPLAY 0.617021 (4775 2950);
PAINT AQUA (4775 2950);
FORCEPROP 1 LAST VALUE 100UF
J 0
(4775 2900);
DISPLAY 0.617021 (4775 2900);
PAINT SKYBLUE (4775 2900);
FORCEPROP 1 LASTPIN (4725 2950) $PN 1
J 0
(4735 2930);
DISPLAY 0.617021 (4735 2930);
PAINT ORANGE (4735 2930);
FORCEPROP 1 LASTPIN (4725 2750) $PN 2
J 0
(4735 2730);
DISPLAY 0.617021 (4735 2730);
PAINT ORANGE (4735 2730);
FORCEPROP 1 LAST VOLTAGE 4V
J 0
(4775 2850);
DISPLAY 0.617021 (4775 2850);
PAINT SKYBLUE (4775 2850);
FORCEPROP 1 LAST PART_NUMBER 602433-112
J 0
(4775 2750);
DISPLAY 0.617021 (4775 2750);
PAINT BLUE (4775 2750);
FORCEPROP 1 LAST TOLERANCE 20%
J 0
(4775 2800);
DISPLAY 0.617021 (4775 2800);
PAINT SKYBLUE (4775 2800);
FORCEPROP 0 LAST NEW_MATERIAL X6S
J 0
(4775 2400);
DISPLAY 0.638298 (4775 2400);
PAINT BROWN (4775 2400);
DISPLAY BOTH (4775 2400);
FORCEPROP 0 LAST BOM_SS NOPOP
J 0
(4775 2350);
DISPLAY 0.638298 (4775 2350);
PAINT BROWN (4775 2350);
DISPLAY BOTH (4775 2350);
FORCEPROP 0 LAST GROUP PWR_MLCC_CAP
J 0
(4781 2312);
DISPLAY 0.638298 (4781 2312);
PAINT BROWN (4781 2312);
DISPLAY BOTH (4781 2312);
FORCEPROP 0 LAST NEW_PN 078.1071T.M002
J 0
(4777 2461);
DISPLAY 0.638298 (4777 2461);
PAINT BROWN (4777 2461);
DISPLAY BOTH (4777 2461);
FORCEPROP 1 LAST PATH I316
J 0
(4775 3000);
DISPLAY 0.978723 (4775 3000);
PAINT WHITE (4775 3000);
DISPLAY INVISIBLE (4775 3000);
FORCEPROP 0 LAST CDS_SEC 1
J 0
(4775 3000);
PAINT MONO (4775 3000);
DISPLAY INVISIBLE (4775 3000);
FORCEPROP 2 LAST CDS_LIB mstr_discrete
J 0
(4725 2850);
PAINT MONO (4725 2850);
DISPLAY INVISIBLE (4725 2850);
FORCEPROP 2 LAST BOM_COST MEM_VRD_PVDDQ_CD
J 0
(4775 3000);
PAINT MONO (4775 3000);
DISPLAY INVISIBLE (4775 3000);
FORCEPROP 2 LAST ROOM VDDQ_ABC_PWR_VR
J 0
(4775 3000);
PAINT MONO (4775 3000);
DISPLAY INVISIBLE (4775 3000);
FORCEPROP 2 LAST SEC_TYPE 0805
J 0
(4775 3050);
DISPLAY 1.021277 (4775 3050);
PAINT ORANGE (4775 3050);
DISPLAY INVISIBLE (4775 3050);
FORCEPROP 2 LAST SEC 1
J 0
(4775 3050);
DISPLAY 0.680851 (4775 3050);
PAINT MONO (4775 3050);
DISPLAY INVISIBLE (4775 3050);
FORCEPROP 1 LAST MATERIAL X5R
J 0
(4775 2750);
DISPLAY 0.617021 (4775 2750);
PAINT SKYBLUE (4775 2750);
DISPLAY INVISIBLE (4775 2750);
FORCEPROP 2 LAST CDS_LOCATION C5U1
J 0
(4775 2950);
DISPLAY 0.617021 (4775 2950);
PAINT AQUA (4775 2950);
DISPLAY INVISIBLE (4775 2950);
FORCEADD CAP..1
(5075 2850);
FORCEPROP 1 LAST VALUE 100UF
J 0
(5125 2900);
DISPLAY 0.617021 (5125 2900);
PAINT SKYBLUE (5125 2900);
FORCEPROP 1 LAST TOLERANCE 20%
J 0
(5125 2800);
DISPLAY 0.617021 (5125 2800);
PAINT SKYBLUE (5125 2800);
FORCEPROP 1 LAST LOCATION C5U10
J 0
(5125 2950);
DISPLAY 0.617021 (5125 2950);
PAINT AQUA (5125 2950);
FORCEPROP 1 LAST VOLTAGE 4V
J 0
(5125 2850);
DISPLAY 0.617021 (5125 2850);
PAINT SKYBLUE (5125 2850);
FORCEPROP 1 LASTPIN (5075 2950) $PN 1
J 0
(5085 2930);
DISPLAY 0.617021 (5085 2930);
PAINT ORANGE (5085 2930);
FORCEPROP 1 LASTPIN (5075 2750) $PN 2
J 0
(5085 2730);
DISPLAY 0.617021 (5085 2730);
PAINT ORANGE (5085 2730);
FORCEPROP 1 LAST PART_NUMBER 602433-112
J 0
(5125 2750);
DISPLAY 0.617021 (5125 2750);
PAINT BLUE (5125 2750);
FORCEPROP 0 LAST BOM_SS NOPOP
J 0
(5125 2550);
DISPLAY 0.638298 (5125 2550);
PAINT BROWN (5125 2550);
DISPLAY BOTH (5125 2550);
FORCEPROP 0 LAST GROUP PWR_MLCC_CAP
J 0
(5131 2512);
DISPLAY 0.638298 (5131 2512);
PAINT BROWN (5131 2512);
DISPLAY BOTH (5131 2512);
FORCEPROP 1 LAST PACK_TYPE 0805
J 0
(5125 2700);
DISPLAY 0.617021 (5125 2700);
PAINT SKYBLUE (5125 2700);
FORCEPROP 0 LAST NEW_MATERIAL X6S
J 0
(5125 2600);
DISPLAY 0.638298 (5125 2600);
PAINT BROWN (5125 2600);
DISPLAY BOTH (5125 2600);
FORCEPROP 0 LAST NEW_PN 078.1071T.M002
J 0
(5127 2661);
DISPLAY 0.638298 (5127 2661);
PAINT BROWN (5127 2661);
DISPLAY BOTH (5127 2661);
FORCEPROP 0 LAST CDS_SEC 1
J 0
(5125 3000);
PAINT MONO (5125 3000);
DISPLAY INVISIBLE (5125 3000);
FORCEPROP 2 LAST CDS_LIB mstr_discrete
J 0
(5075 2850);
PAINT MONO (5075 2850);
DISPLAY INVISIBLE (5075 2850);
FORCEPROP 2 LAST BOM_COST MEM_VRD_PVDDQ_CD
J 0
(5125 3000);
PAINT MONO (5125 3000);
DISPLAY INVISIBLE (5125 3000);
FORCEPROP 2 LAST ROOM VDDQ_ABC_PWR_VR
J 0
(5125 3000);
PAINT MONO (5125 3000);
DISPLAY INVISIBLE (5125 3000);
FORCEPROP 2 LAST SEC_TYPE 0805
J 0
(5125 3050);
DISPLAY 1.021277 (5125 3050);
PAINT ORANGE (5125 3050);
DISPLAY INVISIBLE (5125 3050);
FORCEPROP 2 LAST SEC 1
J 0
(5125 3050);
DISPLAY 0.680851 (5125 3050);
PAINT MONO (5125 3050);
DISPLAY INVISIBLE (5125 3050);
FORCEPROP 1 LAST MATERIAL X5R
J 0
(5125 2750);
DISPLAY 0.617021 (5125 2750);
PAINT SKYBLUE (5125 2750);
DISPLAY INVISIBLE (5125 2750);
FORCEPROP 1 LAST PATH I317
J 0
(5125 3000);
DISPLAY 0.978723 (5125 3000);
PAINT WHITE (5125 3000);
DISPLAY INVISIBLE (5125 3000);
FORCEPROP 2 LAST CDS_LOCATION C5U10
J 0
(5125 2950);
DISPLAY 0.617021 (5125 2950);
PAINT AQUA (5125 2950);
DISPLAY INVISIBLE (5125 2950);
FORCEADD CAP..1
(3225 2850);
FORCEPROP 0 LAST BOM_SS NOPOP
J 0
(3275 2350);
DISPLAY 0.638298 (3275 2350);
PAINT BROWN (3275 2350);
DISPLAY BOTH (3275 2350);
FORCEPROP 1 LAST VALUE 100UF
J 0
(3275 2900);
DISPLAY 0.617021 (3275 2900);
PAINT SKYBLUE (3275 2900);
FORCEPROP 1 LAST LOCATION C5G9
J 0
(3275 2950);
DISPLAY 0.617021 (3275 2950);
PAINT AQUA (3275 2950);
FORCEPROP 1 LASTPIN (3225 2750) $PN 2
J 0
(3235 2730);
DISPLAY 0.617021 (3235 2730);
PAINT ORANGE (3235 2730);
FORCEPROP 1 LASTPIN (3225 2950) $PN 1
J 0
(3235 2930);
DISPLAY 0.617021 (3235 2930);
PAINT ORANGE (3235 2930);
FORCEPROP 0 LAST NEW_MATERIAL X6S
J 0
(3275 2400);
DISPLAY 0.638298 (3275 2400);
PAINT BROWN (3275 2400);
DISPLAY BOTH (3275 2400);
FORCEPROP 0 LAST GROUP PWR_MLCC_CAP
J 0
(3281 2312);
DISPLAY 0.638298 (3281 2312);
PAINT BROWN (3281 2312);
DISPLAY BOTH (3281 2312);
FORCEPROP 0 LAST NEW_PN 078.1071T.M002
J 0
(3277 2461);
DISPLAY 0.638298 (3277 2461);
PAINT BROWN (3277 2461);
DISPLAY BOTH (3277 2461);
FORCEPROP 1 LAST TOLERANCE 20%
J 0
(3275 2800);
DISPLAY 0.617021 (3275 2800);
PAINT SKYBLUE (3275 2800);
FORCEPROP 1 LAST VOLTAGE 4V
J 0
(3275 2850);
DISPLAY 0.617021 (3275 2850);
PAINT SKYBLUE (3275 2850);
FORCEPROP 1 LAST PART_NUMBER 602433-112
J 0
(3275 2750);
DISPLAY 0.617021 (3275 2750);
PAINT BLUE (3275 2750);
FORCEPROP 1 LAST PACK_TYPE 0805
J 0
(3275 2700);
DISPLAY 0.617021 (3275 2700);
PAINT SKYBLUE (3275 2700);
FORCEPROP 1 LAST MATERIAL X5R
J 0
(3275 2750);
DISPLAY 0.617021 (3275 2750);
PAINT SKYBLUE (3275 2750);
DISPLAY INVISIBLE (3275 2750);
FORCEPROP 2 LAST ROOM VDDQ_ABC_PWR_VR
J 0
(3275 3000);
PAINT MONO (3275 3000);
DISPLAY INVISIBLE (3275 3000);
FORCEPROP 2 LAST BOM_COST MEM_VRD_PVDDQ_CD
J 0
(3275 3000);
PAINT MONO (3275 3000);
DISPLAY INVISIBLE (3275 3000);
FORCEPROP 1 LAST PATH I318
J 0
(3275 3000);
DISPLAY 0.978723 (3275 3000);
PAINT WHITE (3275 3000);
DISPLAY INVISIBLE (3275 3000);
FORCEPROP 2 LAST SEC 1
J 0
(3275 3050);
DISPLAY 0.680851 (3275 3050);
PAINT MONO (3275 3050);
DISPLAY INVISIBLE (3275 3050);
FORCEPROP 2 LAST SEC_TYPE 0805
J 0
(3275 3050);
DISPLAY 1.021277 (3275 3050);
PAINT ORANGE (3275 3050);
DISPLAY INVISIBLE (3275 3050);
FORCEPROP 2 LAST CDS_LIB mstr_discrete
J 0
(3225 2850);
PAINT MONO (3225 2850);
DISPLAY INVISIBLE (3225 2850);
FORCEPROP 0 LAST CDS_SEC 1
J 0
(3275 3000);
PAINT MONO (3275 3000);
DISPLAY INVISIBLE (3275 3000);
FORCEPROP 2 LAST CDS_LOCATION C5G9
J 0
(3275 2950);
DISPLAY 0.617021 (3275 2950);
PAINT AQUA (3275 2950);
DISPLAY INVISIBLE (3275 2950);
FORCEADD CAP..1
(3625 2850);
FORCEPROP 1 LASTPIN (3625 2950) $PN 1
J 0
(3635 2930);
DISPLAY 0.617021 (3635 2930);
PAINT ORANGE (3635 2930);
FORCEPROP 1 LAST PACK_TYPE 0805
J 0
(3675 2700);
DISPLAY 0.617021 (3675 2700);
PAINT SKYBLUE (3675 2700);
FORCEPROP 1 LAST VOLTAGE 4V
J 0
(3675 2850);
DISPLAY 0.617021 (3675 2850);
PAINT SKYBLUE (3675 2850);
FORCEPROP 1 LASTPIN (3625 2750) $PN 2
J 0
(3635 2730);
DISPLAY 0.617021 (3635 2730);
PAINT ORANGE (3635 2730);
FORCEPROP 0 LAST GROUP PWR_MLCC_CAP
J 0
(3681 2512);
DISPLAY 0.638298 (3681 2512);
PAINT BROWN (3681 2512);
DISPLAY BOTH (3681 2512);
FORCEPROP 1 LAST LOCATION C4T4
J 0
(3675 2950);
DISPLAY 0.617021 (3675 2950);
PAINT AQUA (3675 2950);
FORCEPROP 1 LAST VALUE 100UF
J 0
(3675 2900);
DISPLAY 0.617021 (3675 2900);
PAINT SKYBLUE (3675 2900);
FORCEPROP 0 LAST BOM_SS NOPOP
J 0
(3675 2550);
DISPLAY 0.638298 (3675 2550);
PAINT BROWN (3675 2550);
DISPLAY BOTH (3675 2550);
FORCEPROP 0 LAST NEW_MATERIAL X6S
J 0
(3675 2600);
DISPLAY 0.638298 (3675 2600);
PAINT BROWN (3675 2600);
DISPLAY BOTH (3675 2600);
FORCEPROP 0 LAST NEW_PN 078.1071T.M002
J 0
(3677 2661);
DISPLAY 0.638298 (3677 2661);
PAINT BROWN (3677 2661);
DISPLAY BOTH (3677 2661);
FORCEPROP 1 LAST PART_NUMBER 602433-112
J 0
(3675 2750);
DISPLAY 0.617021 (3675 2750);
PAINT BLUE (3675 2750);
FORCEPROP 1 LAST TOLERANCE 20%
J 0
(3675 2800);
DISPLAY 0.617021 (3675 2800);
PAINT SKYBLUE (3675 2800);
FORCEPROP 0 LAST CDS_SEC 1
J 0
(3675 3000);
PAINT MONO (3675 3000);
DISPLAY INVISIBLE (3675 3000);
FORCEPROP 2 LAST CDS_LIB mstr_discrete
J 0
(3625 2850);
PAINT MONO (3625 2850);
DISPLAY INVISIBLE (3625 2850);
FORCEPROP 2 LAST BOM_COST MEM_VRD_PVDDQ_CD
J 0
(3675 3000);
PAINT MONO (3675 3000);
DISPLAY INVISIBLE (3675 3000);
FORCEPROP 2 LAST ROOM VDDQ_ABC_PWR_VR
J 0
(3675 3000);
PAINT MONO (3675 3000);
DISPLAY INVISIBLE (3675 3000);
FORCEPROP 2 LAST SEC_TYPE 0805
J 0
(3675 3050);
DISPLAY 1.021277 (3675 3050);
PAINT ORANGE (3675 3050);
DISPLAY INVISIBLE (3675 3050);
FORCEPROP 2 LAST SEC 1
J 0
(3675 3050);
DISPLAY 0.680851 (3675 3050);
PAINT MONO (3675 3050);
DISPLAY INVISIBLE (3675 3050);
FORCEPROP 1 LAST MATERIAL X5R
J 0
(3675 2750);
DISPLAY 0.617021 (3675 2750);
PAINT SKYBLUE (3675 2750);
DISPLAY INVISIBLE (3675 2750);
FORCEPROP 1 LAST PATH I319
J 0
(3675 3000);
DISPLAY 0.978723 (3675 3000);
PAINT WHITE (3675 3000);
DISPLAY INVISIBLE (3675 3000);
FORCEPROP 2 LAST CDS_LOCATION C4T4
J 0
(3675 2950);
DISPLAY 0.617021 (3675 2950);
PAINT AQUA (3675 2950);
DISPLAY INVISIBLE (3675 2950);
FORCEADD CAP..1
(3975 2850);
FORCEPROP 1 LAST LOCATION C5U15
J 0
(4025 2950);
DISPLAY 0.617021 (4025 2950);
PAINT AQUA (4025 2950);
FORCEPROP 1 LAST TOLERANCE 20%
J 0
(4025 2800);
DISPLAY 0.617021 (4025 2800);
PAINT SKYBLUE (4025 2800);
FORCEPROP 1 LAST VALUE 100UF
J 0
(4025 2900);
DISPLAY 0.617021 (4025 2900);
PAINT SKYBLUE (4025 2900);
FORCEPROP 1 LAST VOLTAGE 4V
J 0
(4025 2850);
DISPLAY 0.617021 (4025 2850);
PAINT SKYBLUE (4025 2850);
FORCEPROP 1 LASTPIN (3975 2950) $PN 1
J 0
(3985 2930);
DISPLAY 0.787234 (3985 2930);
PAINT ORANGE (3985 2930);
FORCEPROP 0 LAST BOM_SS NOPOP
J 0
(4025 2350);
DISPLAY 0.638298 (4025 2350);
PAINT BROWN (4025 2350);
DISPLAY BOTH (4025 2350);
FORCEPROP 1 LASTPIN (3975 2750) $PN 2
J 0
(3985 2730);
DISPLAY 0.787234 (3985 2730);
PAINT ORANGE (3985 2730);
FORCEPROP 1 LAST PACK_TYPE 0805
J 0
(4025 2700);
DISPLAY 0.617021 (4025 2700);
PAINT SKYBLUE (4025 2700);
FORCEPROP 1 LAST PART_NUMBER 602433-112
J 0
(4025 2750);
DISPLAY 0.617021 (4025 2750);
PAINT BLUE (4025 2750);
FORCEPROP 0 LAST GROUP PWR_MLCC_CAP
J 0
(4031 2312);
DISPLAY 0.638298 (4031 2312);
PAINT BROWN (4031 2312);
DISPLAY BOTH (4031 2312);
FORCEPROP 0 LAST NEW_MATERIAL X6S
J 0
(4025 2400);
DISPLAY 0.638298 (4025 2400);
PAINT BROWN (4025 2400);
DISPLAY BOTH (4025 2400);
FORCEPROP 0 LAST NEW_PN 078.1071T.M002
J 0
(4027 2461);
DISPLAY 0.638298 (4027 2461);
PAINT BROWN (4027 2461);
DISPLAY BOTH (4027 2461);
FORCEPROP 2 LAST SEC 1
J 0
(4025 3050);
DISPLAY 0.680851 (4025 3050);
PAINT MONO (4025 3050);
DISPLAY INVISIBLE (4025 3050);
FORCEPROP 2 LAST SEC_TYPE 0805
J 0
(4025 3050);
DISPLAY 1.021277 (4025 3050);
PAINT ORANGE (4025 3050);
DISPLAY INVISIBLE (4025 3050);
FORCEPROP 2 LAST CDS_LIB mstr_discrete
J 0
(3975 2850);
DISPLAY INVISIBLE (3975 2850);
FORCEPROP 1 LAST PATH I320
J 0
(4025 3000);
DISPLAY 0.978723 (4025 3000);
PAINT WHITE (4025 3000);
DISPLAY INVISIBLE (4025 3000);
FORCEPROP 1 LAST MATERIAL X5R
J 0
(4025 2750);
DISPLAY 0.617021 (4025 2750);
PAINT SKYBLUE (4025 2750);
DISPLAY INVISIBLE (4025 2750);
FORCEPROP 2 LAST ROOM VDDQ_ABC_PWR_VR
J 0
(4025 3000);
PAINT MONO (4025 3000);
DISPLAY INVISIBLE (4025 3000);
FORCEPROP 2 LAST BOM_COST MEM_VRD_PVDDQ_CD
J 0
(4025 3000);
PAINT MONO (4025 3000);
DISPLAY INVISIBLE (4025 3000);
FORCEADD CAP..1
(5475 2850);
FORCEPROP 1 LAST TOLERANCE 20%
J 0
(5525 2800);
DISPLAY 0.617021 (5525 2800);
PAINT SKYBLUE (5525 2800);
FORCEPROP 1 LAST VOLTAGE 4V
J 0
(5525 2850);
DISPLAY 0.617021 (5525 2850);
PAINT SKYBLUE (5525 2850);
FORCEPROP 1 LAST PART_NUMBER 602433-112
J 0
(5525 2750);
DISPLAY 0.617021 (5525 2750);
PAINT BLUE (5525 2750);
FORCEPROP 1 LAST PACK_TYPE 0805
J 0
(5525 2700);
DISPLAY 0.617021 (5525 2700);
PAINT SKYBLUE (5525 2700);
FORCEPROP 1 LASTPIN (5475 2950) $PN 1
J 0
(5485 2930);
DISPLAY 0.617021 (5485 2930);
PAINT ORANGE (5485 2930);
FORCEPROP 1 LASTPIN (5475 2750) $PN 2
J 0
(5485 2730);
DISPLAY 0.617021 (5485 2730);
PAINT ORANGE (5485 2730);
FORCEPROP 1 LAST VALUE 100UF
J 0
(5525 2900);
DISPLAY 0.617021 (5525 2900);
PAINT SKYBLUE (5525 2900);
FORCEPROP 1 LAST LOCATION C5U13
J 0
(5525 2950);
DISPLAY 0.617021 (5525 2950);
PAINT AQUA (5525 2950);
FORCEPROP 0 LAST NEW_MATERIAL X6S
J 0
(5525 2400);
DISPLAY 0.638298 (5525 2400);
PAINT BROWN (5525 2400);
DISPLAY BOTH (5525 2400);
FORCEPROP 0 LAST BOM_SS NOPOP
J 0
(5525 2350);
DISPLAY 0.638298 (5525 2350);
PAINT BROWN (5525 2350);
DISPLAY BOTH (5525 2350);
FORCEPROP 0 LAST GROUP PWR_MLCC_CAP
J 0
(5531 2312);
DISPLAY 0.638298 (5531 2312);
PAINT BROWN (5531 2312);
DISPLAY BOTH (5531 2312);
FORCEPROP 0 LAST NEW_PN 078.1071T.M002
J 0
(5527 2461);
DISPLAY 0.638298 (5527 2461);
PAINT BROWN (5527 2461);
DISPLAY BOTH (5527 2461);
FORCEPROP 0 LAST CDS_SEC 1
J 0
(5525 3000);
PAINT MONO (5525 3000);
DISPLAY INVISIBLE (5525 3000);
FORCEPROP 2 LAST CDS_LIB mstr_discrete
J 0
(5475 2850);
PAINT MONO (5475 2850);
DISPLAY INVISIBLE (5475 2850);
FORCEPROP 2 LAST BOM_COST MEM_VRD_PVDDQ_CD
J 0
(5525 3000);
PAINT MONO (5525 3000);
DISPLAY INVISIBLE (5525 3000);
FORCEPROP 2 LAST ROOM VDDQ_ABC_PWR_VR
J 0
(5525 3000);
PAINT MONO (5525 3000);
DISPLAY INVISIBLE (5525 3000);
FORCEPROP 2 LAST SEC_TYPE 0805
J 0
(5525 3050);
DISPLAY 1.021277 (5525 3050);
PAINT ORANGE (5525 3050);
DISPLAY INVISIBLE (5525 3050);
FORCEPROP 2 LAST SEC 1
J 0
(5525 3050);
DISPLAY 0.680851 (5525 3050);
PAINT MONO (5525 3050);
DISPLAY INVISIBLE (5525 3050);
FORCEPROP 1 LAST MATERIAL X5R
J 0
(5525 2750);
DISPLAY 0.617021 (5525 2750);
PAINT SKYBLUE (5525 2750);
DISPLAY INVISIBLE (5525 2750);
FORCEPROP 1 LAST PATH I321
J 0
(5525 3000);
DISPLAY 0.978723 (5525 3000);
PAINT WHITE (5525 3000);
DISPLAY INVISIBLE (5525 3000);
FORCEPROP 2 LAST CDS_LOCATION C5U13
J 0
(5525 2950);
DISPLAY 0.617021 (5525 2950);
PAINT AQUA (5525 2950);
DISPLAY INVISIBLE (5525 2950);
FORCEADD CAP..1
(4325 2850);
FORCEPROP 0 LAST BOM_SS NOPOP
J 0
(4375 2550);
DISPLAY 0.638298 (4375 2550);
PAINT BROWN (4375 2550);
DISPLAY BOTH (4375 2550);
FORCEPROP 1 LAST VOLTAGE 4V
J 0
(4375 2850);
DISPLAY 0.617021 (4375 2850);
PAINT SKYBLUE (4375 2850);
FORCEPROP 0 LAST NEW_MATERIAL X6S
J 0
(4375 2600);
DISPLAY 0.638298 (4375 2600);
PAINT BROWN (4375 2600);
DISPLAY BOTH (4375 2600);
FORCEPROP 1 LASTPIN (4325 2950) $PN 1
J 0
(4335 2930);
DISPLAY 0.617021 (4335 2930);
PAINT ORANGE (4335 2930);
FORCEPROP 1 LASTPIN (4325 2750) $PN 2
J 0
(4335 2730);
DISPLAY 0.617021 (4335 2730);
PAINT ORANGE (4335 2730);
FORCEPROP 1 LAST LOCATION C5U14
J 0
(4375 2950);
DISPLAY 0.617021 (4375 2950);
PAINT AQUA (4375 2950);
FORCEPROP 1 LAST PACK_TYPE 0805
J 0
(4375 2700);
DISPLAY 0.617021 (4375 2700);
PAINT SKYBLUE (4375 2700);
FORCEPROP 1 LAST PART_NUMBER 602433-112
J 0
(4375 2750);
DISPLAY 0.617021 (4375 2750);
PAINT BLUE (4375 2750);
FORCEPROP 0 LAST GROUP PWR_MLCC_CAP
J 0
(4381 2512);
DISPLAY 0.638298 (4381 2512);
PAINT BROWN (4381 2512);
DISPLAY BOTH (4381 2512);
FORCEPROP 1 LAST TOLERANCE 20%
J 0
(4375 2800);
DISPLAY 0.617021 (4375 2800);
PAINT SKYBLUE (4375 2800);
FORCEPROP 1 LAST VALUE 100UF
J 0
(4375 2900);
DISPLAY 0.617021 (4375 2900);
PAINT SKYBLUE (4375 2900);
FORCEPROP 0 LAST NEW_PN 078.1071T.M002
J 0
(4377 2636);
DISPLAY 0.638298 (4377 2636);
PAINT BROWN (4377 2636);
DISPLAY BOTH (4377 2636);
FORCEPROP 1 LAST PATH I322
J 0
(4375 3000);
DISPLAY 0.978723 (4375 3000);
PAINT WHITE (4375 3000);
DISPLAY INVISIBLE (4375 3000);
FORCEPROP 0 LAST CDS_SEC 1
J 0
(4375 3000);
PAINT MONO (4375 3000);
DISPLAY INVISIBLE (4375 3000);
FORCEPROP 2 LAST CDS_LIB mstr_discrete
J 0
(4325 2850);
PAINT MONO (4325 2850);
DISPLAY INVISIBLE (4325 2850);
FORCEPROP 2 LAST BOM_COST MEM_VRD_PVDDQ_CD
J 0
(4375 3000);
PAINT MONO (4375 3000);
DISPLAY INVISIBLE (4375 3000);
FORCEPROP 2 LAST ROOM VDDQ_ABC_PWR_VR
J 0
(4375 3000);
PAINT MONO (4375 3000);
DISPLAY INVISIBLE (4375 3000);
FORCEPROP 2 LAST SEC_TYPE 0805
J 0
(4375 3050);
DISPLAY 1.021277 (4375 3050);
PAINT ORANGE (4375 3050);
DISPLAY INVISIBLE (4375 3050);
FORCEPROP 2 LAST SEC 1
J 0
(4375 3050);
DISPLAY 0.680851 (4375 3050);
PAINT MONO (4375 3050);
DISPLAY INVISIBLE (4375 3050);
FORCEPROP 1 LAST MATERIAL X5R
J 0
(4375 2750);
DISPLAY 0.617021 (4375 2750);
PAINT SKYBLUE (4375 2750);
DISPLAY INVISIBLE (4375 2750);
FORCEPROP 2 LAST CDS_LOCATION C5U14
J 0
(4375 2950);
DISPLAY 0.617021 (4375 2950);
PAINT AQUA (4375 2950);
DISPLAY INVISIBLE (4375 2950);
FORCEADD CAP..1
(2000 2875);
FORCEPROP 0 LAST NEW_PN 078.1071T.M002
J 0
(2052 2686);
DISPLAY 0.638298 (2052 2686);
PAINT BROWN (2052 2686);
DISPLAY BOTH (2052 2686);
FORCEPROP 1 LAST PACK_TYPE 0805
J 0
(2050 2725);
DISPLAY 0.617021 (2050 2725);
PAINT SKYBLUE (2050 2725);
FORCEPROP 0 LAST NEW_MATERIAL X6S
J 0
(2050 2625);
DISPLAY 0.638298 (2050 2625);
PAINT BROWN (2050 2625);
DISPLAY BOTH (2050 2625);
FORCEPROP 0 LAST GROUP PWR_MLCC_CAP
J 0
(2056 2587);
DISPLAY 0.638298 (2056 2587);
PAINT BROWN (2056 2587);
DISPLAY BOTH (2056 2587);
FORCEPROP 1 LAST TOLERANCE 20%
J 0
(2050 2825);
DISPLAY 0.617021 (2050 2825);
PAINT SKYBLUE (2050 2825);
FORCEPROP 0 LAST BOM_SS NOPOP
J 0
(2050 2525);
DISPLAY 0.638298 (2050 2525);
PAINT BROWN (2050 2525);
DISPLAY BOTH (2050 2525);
FORCEPROP 1 LASTPIN (2000 2975) $PN 1
J 0
(2010 2955);
DISPLAY 0.617021 (2010 2955);
PAINT ORANGE (2010 2955);
FORCEPROP 1 LASTPIN (2000 2775) $PN 2
J 0
(2010 2755);
DISPLAY 0.617021 (2010 2755);
PAINT ORANGE (2010 2755);
FORCEPROP 1 LAST LOCATION C5P41
J 0
(2050 2975);
DISPLAY 0.617021 (2050 2975);
PAINT AQUA (2050 2975);
FORCEPROP 1 LAST VOLTAGE 4V
J 0
(2050 2875);
DISPLAY 0.617021 (2050 2875);
PAINT SKYBLUE (2050 2875);
FORCEPROP 1 LAST VALUE 100UF
J 0
(2050 2925);
DISPLAY 0.617021 (2050 2925);
PAINT SKYBLUE (2050 2925);
FORCEPROP 1 LAST PART_NUMBER 602433-112
J 0
(2050 2775);
DISPLAY 0.617021 (2050 2775);
PAINT BLUE (2050 2775);
FORCEPROP 1 LAST PATH I323
J 0
(2050 3025);
DISPLAY 0.978723 (2050 3025);
PAINT WHITE (2050 3025);
DISPLAY INVISIBLE (2050 3025);
FORCEPROP 0 LAST CDS_SEC 1
J 0
(2050 3025);
PAINT MONO (2050 3025);
DISPLAY INVISIBLE (2050 3025);
FORCEPROP 2 LAST CDS_LIB mstr_discrete
J 0
(2000 2875);
PAINT MONO (2000 2875);
DISPLAY INVISIBLE (2000 2875);
FORCEPROP 2 LAST BOM_COST MEM_VRD_PVDDQ_CD
J 0
(2050 3025);
PAINT MONO (2050 3025);
DISPLAY INVISIBLE (2050 3025);
FORCEPROP 2 LAST ROOM VDDQ_ABC_PWR_VR
J 0
(2050 3025);
PAINT MONO (2050 3025);
DISPLAY INVISIBLE (2050 3025);
FORCEPROP 2 LAST SEC_TYPE 0805
J 0
(2050 3075);
DISPLAY 1.021277 (2050 3075);
PAINT ORANGE (2050 3075);
DISPLAY INVISIBLE (2050 3075);
FORCEPROP 2 LAST SEC 1
J 0
(2050 3075);
DISPLAY 0.680851 (2050 3075);
PAINT MONO (2050 3075);
DISPLAY INVISIBLE (2050 3075);
FORCEPROP 1 LAST MATERIAL X5R
J 0
(2050 2775);
DISPLAY 0.617021 (2050 2775);
PAINT SKYBLUE (2050 2775);
DISPLAY INVISIBLE (2050 2775);
FORCEPROP 2 LAST CDS_LOCATION C5P41
J 0
(2050 2975);
DISPLAY 0.617021 (2050 2975);
PAINT AQUA (2050 2975);
DISPLAY INVISIBLE (2050 2975);
FORCEADD CAP..1
(700 2850);
FORCEPROP 1 LAST PACK_TYPE 0805
J 0
(750 2700);
DISPLAY 0.617021 (750 2700);
PAINT SKYBLUE (750 2700);
FORCEPROP 1 LAST LOCATION C5P44
J 0
(750 2950);
DISPLAY 0.617021 (750 2950);
PAINT AQUA (750 2950);
FORCEPROP 1 LAST VALUE 100UF
J 0
(750 2900);
DISPLAY 0.617021 (750 2900);
PAINT SKYBLUE (750 2900);
FORCEPROP 1 LAST VOLTAGE 4V
J 0
(750 2850);
DISPLAY 0.617021 (750 2850);
PAINT SKYBLUE (750 2850);
FORCEPROP 1 LAST TOLERANCE 20%
J 0
(750 2800);
DISPLAY 0.617021 (750 2800);
PAINT SKYBLUE (750 2800);
FORCEPROP 1 LASTPIN (700 2750) $PN 2
J 0
(710 2730);
DISPLAY 0.617021 (710 2730);
PAINT ORANGE (710 2730);
FORCEPROP 1 LASTPIN (700 2950) $PN 1
J 0
(710 2930);
DISPLAY 0.617021 (710 2930);
PAINT ORANGE (710 2930);
FORCEPROP 1 LAST PART_NUMBER 602433-112
J 0
(750 2750);
DISPLAY 0.617021 (750 2750);
PAINT BLUE (750 2750);
FORCEPROP 0 LAST BOM_SS NOPOP
J 0
(725 2650);
DISPLAY 0.638298 (725 2650);
PAINT BROWN (725 2650);
DISPLAY BOTH (725 2650);
FORCEPROP 0 LAST NEW_MATERIAL X6S
J 0
(750 2425);
DISPLAY 0.638298 (750 2425);
PAINT BROWN (750 2425);
DISPLAY BOTH (750 2425);
FORCEPROP 0 LAST NEW_PN 078.1071T.M002
J 0
(752 2486);
DISPLAY 0.638298 (752 2486);
PAINT BROWN (752 2486);
DISPLAY BOTH (752 2486);
FORCEPROP 0 LAST GROUP PWR_MLCC_CAP
J 0
(731 2537);
DISPLAY 0.638298 (731 2537);
PAINT BROWN (731 2537);
DISPLAY BOTH (731 2537);
FORCEPROP 1 LAST PATH I324
J 0
(750 3000);
DISPLAY 0.978723 (750 3000);
PAINT WHITE (750 3000);
DISPLAY INVISIBLE (750 3000);
FORCEPROP 1 LAST MATERIAL X5R
J 0
(750 2750);
DISPLAY 0.617021 (750 2750);
PAINT SKYBLUE (750 2750);
DISPLAY INVISIBLE (750 2750);
FORCEPROP 2 LAST SEC 1
J 0
(750 3050);
DISPLAY 0.680851 (750 3050);
PAINT MONO (750 3050);
DISPLAY INVISIBLE (750 3050);
FORCEPROP 2 LAST SEC_TYPE 0805
J 0
(750 3050);
DISPLAY 1.021277 (750 3050);
PAINT ORANGE (750 3050);
DISPLAY INVISIBLE (750 3050);
FORCEPROP 2 LAST ROOM VDDQ_ABC_PWR_VR
J 0
(750 3000);
PAINT MONO (750 3000);
DISPLAY INVISIBLE (750 3000);
FORCEPROP 2 LAST BOM_COST MEM_VRD_PVDDQ_CD
J 0
(750 3000);
PAINT MONO (750 3000);
DISPLAY INVISIBLE (750 3000);
FORCEPROP 2 LAST CDS_LIB mstr_discrete
J 0
(700 2850);
PAINT MONO (700 2850);
DISPLAY INVISIBLE (700 2850);
FORCEPROP 0 LAST CDS_SEC 1
J 0
(750 3000);
PAINT MONO (750 3000);
DISPLAY INVISIBLE (750 3000);
FORCEPROP 2 LAST CDS_LOCATION C5P44
J 0
(750 2950);
DISPLAY 0.617021 (750 2950);
PAINT AQUA (750 2950);
DISPLAY INVISIBLE (750 2950);
FORCEADD CAP..1
(1375 2850);
FORCEPROP 0 LAST NEW_PN 078.1071T.M002
J 0
(1302 2486);
DISPLAY 0.638298 (1302 2486);
PAINT BROWN (1302 2486);
DISPLAY BOTH (1302 2486);
FORCEPROP 0 LAST GROUP PWR_MLCC_CAP
J 0
(1306 2512);
DISPLAY 0.638298 (1306 2512);
PAINT BROWN (1306 2512);
DISPLAY BOTH (1306 2512);
FORCEPROP 0 LAST BOM_SS NOPOP
J 0
(1400 3000);
DISPLAY 0.638298 (1400 3000);
PAINT BROWN (1400 3000);
DISPLAY BOTH (1400 3000);
FORCEPROP 1 LAST LOCATION C5P42
J 0
(1425 2950);
DISPLAY 0.617021 (1425 2950);
PAINT AQUA (1425 2950);
FORCEPROP 1 LAST VOLTAGE 4V
J 0
(1425 2850);
DISPLAY 0.617021 (1425 2850);
PAINT SKYBLUE (1425 2850);
FORCEPROP 1 LAST VALUE 100UF
J 0
(1425 2900);
DISPLAY 0.617021 (1425 2900);
PAINT SKYBLUE (1425 2900);
FORCEPROP 1 LAST PACK_TYPE 0805
J 0
(1425 2700);
DISPLAY 0.617021 (1425 2700);
PAINT SKYBLUE (1425 2700);
FORCEPROP 1 LAST PART_NUMBER 602433-112
J 0
(1425 2750);
DISPLAY 0.617021 (1425 2750);
PAINT BLUE (1425 2750);
FORCEPROP 1 LAST TOLERANCE 20%
J 0
(1425 2800);
DISPLAY 0.617021 (1425 2800);
PAINT SKYBLUE (1425 2800);
FORCEPROP 0 LAST NEW_MATERIAL X6S
J 0
(1300 2425);
DISPLAY 0.638298 (1300 2425);
PAINT BROWN (1300 2425);
DISPLAY BOTH (1300 2425);
FORCEPROP 1 LAST PATH I325
J 0
(1425 3000);
DISPLAY 0.978723 (1425 3000);
PAINT WHITE (1425 3000);
DISPLAY INVISIBLE (1425 3000);
FORCEPROP 2 LAST CDS_LIB mstr_discrete
J 0
(1375 2850);
DISPLAY INVISIBLE (1375 2850);
FORCEPROP 2 LAST BOM_COST MEM_VRD_PVDDQ_CD
J 0
(1425 3000);
PAINT MONO (1425 3000);
DISPLAY INVISIBLE (1425 3000);
FORCEPROP 2 LAST ROOM VDDQ_ABC_PWR_VR
J 0
(1425 3000);
PAINT MONO (1425 3000);
DISPLAY INVISIBLE (1425 3000);
FORCEPROP 1 LAST MATERIAL X5R
J 0
(1425 2750);
DISPLAY 0.617021 (1425 2750);
PAINT SKYBLUE (1425 2750);
DISPLAY INVISIBLE (1425 2750);
FORCEPROP 1 LASTPIN (1375 2750) $PN 2
J 0
(1385 2730);
DISPLAY 0.787234 (1385 2730);
PAINT ORANGE (1385 2730);
DISPLAY INVISIBLE (1385 2730);
FORCEPROP 1 LASTPIN (1375 2950) $PN 1
J 0
(1385 2930);
DISPLAY 0.787234 (1385 2930);
PAINT ORANGE (1385 2930);
DISPLAY INVISIBLE (1385 2930);
FORCEADD CAP..1
(1025 2850);
FORCEPROP 0 LAST BOM_SS NOPOP
J 0
(1075 3050);
DISPLAY 0.638298 (1075 3050);
PAINT BROWN (1075 3050);
DISPLAY BOTH (1075 3050);
FORCEPROP 1 LAST LOCATION C5P43
J 0
(1075 2950);
DISPLAY 0.617021 (1075 2950);
PAINT AQUA (1075 2950);
FORCEPROP 1 LAST VALUE 100UF
J 0
(1075 2900);
DISPLAY 0.617021 (1075 2900);
PAINT SKYBLUE (1075 2900);
FORCEPROP 1 LAST VOLTAGE 4V
J 0
(1075 2850);
DISPLAY 0.617021 (1075 2850);
PAINT SKYBLUE (1075 2850);
FORCEPROP 1 LAST TOLERANCE 20%
J 0
(1075 2800);
DISPLAY 0.617021 (1075 2800);
PAINT SKYBLUE (1075 2800);
FORCEPROP 1 LAST PACK_TYPE 0805
J 0
(1075 2700);
DISPLAY 0.617021 (1075 2700);
PAINT SKYBLUE (1075 2700);
FORCEPROP 1 LAST PART_NUMBER 602433-112
J 0
(1075 2750);
DISPLAY 0.617021 (1075 2750);
PAINT BLUE (1075 2750);
FORCEPROP 0 LAST GROUP PWR_MLCC_CAP
J 0
(1081 2562);
DISPLAY 0.638298 (1081 2562);
PAINT BROWN (1081 2562);
DISPLAY BOTH (1081 2562);
FORCEPROP 0 LAST NEW_MATERIAL X6S
J 0
(1075 2600);
DISPLAY 0.638298 (1075 2600);
PAINT BROWN (1075 2600);
DISPLAY BOTH (1075 2600);
FORCEPROP 0 LAST NEW_PN 078.1071T.M002
J 0
(1077 2661);
DISPLAY 0.638298 (1077 2661);
PAINT BROWN (1077 2661);
DISPLAY BOTH (1077 2661);
FORCEPROP 1 LAST PATH I326
J 0
(1075 3000);
DISPLAY 0.978723 (1075 3000);
PAINT WHITE (1075 3000);
DISPLAY INVISIBLE (1075 3000);
FORCEPROP 1 LAST MATERIAL X5R
J 0
(1075 2750);
DISPLAY 0.617021 (1075 2750);
PAINT SKYBLUE (1075 2750);
DISPLAY INVISIBLE (1075 2750);
FORCEPROP 2 LAST ROOM VDDQ_ABC_PWR_VR
J 0
(1075 3000);
PAINT MONO (1075 3000);
DISPLAY INVISIBLE (1075 3000);
FORCEPROP 2 LAST BOM_COST MEM_VRD_PVDDQ_CD
J 0
(1075 3000);
PAINT MONO (1075 3000);
DISPLAY INVISIBLE (1075 3000);
FORCEPROP 2 LAST CDS_LIB mstr_discrete
J 0
(1025 2850);
DISPLAY INVISIBLE (1025 2850);
FORCEPROP 1 LASTPIN (1025 2750) $PN 2
J 0
(1035 2730);
DISPLAY 0.787234 (1035 2730);
PAINT ORANGE (1035 2730);
DISPLAY INVISIBLE (1035 2730);
FORCEPROP 1 LASTPIN (1025 2950) $PN 1
J 0
(1035 2930);
DISPLAY 0.787234 (1035 2930);
PAINT ORANGE (1035 2930);
DISPLAY INVISIBLE (1035 2930);
FORCEADD CAP..1
(-1400 2850);
FORCEPROP 1 LAST LOCATION C5P38
J 0
(-1350 2950);
DISPLAY 0.617021 (-1350 2950);
PAINT AQUA (-1350 2950);
FORCEPROP 1 LAST VALUE 100UF
J 0
(-1350 2900);
DISPLAY 0.617021 (-1350 2900);
PAINT SKYBLUE (-1350 2900);
FORCEPROP 1 LAST VOLTAGE 4V
J 0
(-1350 2850);
DISPLAY 0.617021 (-1350 2850);
PAINT SKYBLUE (-1350 2850);
FORCEPROP 1 LAST PART_NUMBER 602433-112
J 0
(-1350 2750);
DISPLAY 0.617021 (-1350 2750);
PAINT BLUE (-1350 2750);
FORCEPROP 1 LAST TOLERANCE 20%
J 0
(-1350 2800);
DISPLAY 0.617021 (-1350 2800);
PAINT SKYBLUE (-1350 2800);
FORCEPROP 1 LASTPIN (-1400 2950) $PN 1
J 0
(-1390 2930);
DISPLAY 0.617021 (-1390 2930);
PAINT ORANGE (-1390 2930);
FORCEPROP 0 LAST BOM_SS NOPOP
J 0
(-1400 2350);
DISPLAY 0.638298 (-1400 2350);
PAINT BROWN (-1400 2350);
DISPLAY BOTH (-1400 2350);
FORCEPROP 0 LAST GROUP PWR_MLCC_CAP
J 0
(-1344 2387);
DISPLAY 0.638298 (-1344 2387);
PAINT BROWN (-1344 2387);
DISPLAY BOTH (-1344 2387);
FORCEPROP 0 LAST NEW_MATERIAL X6S
J 0
(-1350 2425);
DISPLAY 0.638298 (-1350 2425);
PAINT BROWN (-1350 2425);
DISPLAY BOTH (-1350 2425);
FORCEPROP 1 LAST PACK_TYPE 0805
J 0
(-1350 2700);
DISPLAY 0.617021 (-1350 2700);
PAINT SKYBLUE (-1350 2700);
FORCEPROP 1 LASTPIN (-1400 2750) $PN 2
J 0
(-1390 2730);
DISPLAY 0.617021 (-1390 2730);
PAINT ORANGE (-1390 2730);
FORCEPROP 0 LAST NEW_PN 078.1071T.M002
J 0
(-1348 2486);
DISPLAY 0.638298 (-1348 2486);
PAINT BROWN (-1348 2486);
DISPLAY BOTH (-1348 2486);
FORCEPROP 1 LAST MATERIAL X5R
J 0
(-1350 2750);
DISPLAY 0.617021 (-1350 2750);
PAINT SKYBLUE (-1350 2750);
DISPLAY INVISIBLE (-1350 2750);
FORCEPROP 2 LAST SEC 1
J 0
(-1350 3050);
DISPLAY 0.680851 (-1350 3050);
PAINT MONO (-1350 3050);
DISPLAY INVISIBLE (-1350 3050);
FORCEPROP 2 LAST SEC_TYPE 0805
J 0
(-1350 3050);
DISPLAY 1.021277 (-1350 3050);
PAINT ORANGE (-1350 3050);
DISPLAY INVISIBLE (-1350 3050);
FORCEPROP 2 LAST ROOM VDDQ_ABC_PWR_VR
J 0
(-1350 3000);
PAINT MONO (-1350 3000);
DISPLAY INVISIBLE (-1350 3000);
FORCEPROP 2 LAST BOM_COST MEM_VRD_PVDDQ_CD
J 0
(-1350 3000);
PAINT MONO (-1350 3000);
DISPLAY INVISIBLE (-1350 3000);
FORCEPROP 2 LAST CDS_LIB mstr_discrete
J 0
(-1400 2850);
PAINT MONO (-1400 2850);
DISPLAY INVISIBLE (-1400 2850);
FORCEPROP 0 LAST CDS_SEC 1
J 0
(-1350 3000);
PAINT MONO (-1350 3000);
DISPLAY INVISIBLE (-1350 3000);
FORCEPROP 1 LAST PATH I327
J 0
(-1350 3000);
DISPLAY 0.978723 (-1350 3000);
PAINT WHITE (-1350 3000);
DISPLAY INVISIBLE (-1350 3000);
FORCEPROP 2 LAST CDS_LOCATION C5P38
J 0
(-1350 2950);
DISPLAY 0.617021 (-1350 2950);
PAINT AQUA (-1350 2950);
DISPLAY INVISIBLE (-1350 2950);
FORCEADD CAP..1
(-1750 2850);
FORCEPROP 1 LAST PART_NUMBER 602433-112
J 0
(-1700 2750);
DISPLAY 0.617021 (-1700 2750);
PAINT BLUE (-1700 2750);
FORCEPROP 1 LAST PACK_TYPE 0805
J 0
(-1700 2700);
DISPLAY 0.617021 (-1700 2700);
PAINT SKYBLUE (-1700 2700);
FORCEPROP 1 LAST TOLERANCE 20%
J 0
(-1700 2800);
DISPLAY 0.617021 (-1700 2800);
PAINT SKYBLUE (-1700 2800);
FORCEPROP 1 LAST VOLTAGE 4V
J 0
(-1700 2850);
DISPLAY 0.617021 (-1700 2850);
PAINT SKYBLUE (-1700 2850);
FORCEPROP 1 LAST VALUE 100UF
J 0
(-1700 2900);
DISPLAY 0.617021 (-1700 2900);
PAINT SKYBLUE (-1700 2900);
FORCEPROP 1 LASTPIN (-1750 2950) $PN 1
J 0
(-1740 2930);
DISPLAY 0.787234 (-1740 2930);
PAINT ORANGE (-1740 2930);
FORCEPROP 1 LAST LOCATION C5P39
J 0
(-1700 2950);
DISPLAY 0.617021 (-1700 2950);
PAINT AQUA (-1700 2950);
FORCEPROP 1 LASTPIN (-1750 2750) $PN 2
J 0
(-1740 2730);
DISPLAY 0.787234 (-1740 2730);
PAINT ORANGE (-1740 2730);
FORCEPROP 0 LAST GROUP PWR_MLCC_CAP
J 0
(-1694 2562);
DISPLAY 0.638298 (-1694 2562);
PAINT BROWN (-1694 2562);
DISPLAY BOTH (-1694 2562);
FORCEPROP 0 LAST BOM_SS NOPOP
J 0
(-1750 2525);
DISPLAY 0.638298 (-1750 2525);
PAINT BROWN (-1750 2525);
DISPLAY BOTH (-1750 2525);
FORCEPROP 0 LAST NEW_MATERIAL X6S
J 0
(-1700 2600);
DISPLAY 0.638298 (-1700 2600);
PAINT BROWN (-1700 2600);
DISPLAY BOTH (-1700 2600);
FORCEPROP 0 LAST NEW_PN 078.1071T.M002
J 0
(-1698 2636);
DISPLAY 0.638298 (-1698 2636);
PAINT BROWN (-1698 2636);
DISPLAY BOTH (-1698 2636);
FORCEPROP 1 LAST MATERIAL X5R
J 0
(-1700 2750);
DISPLAY 0.617021 (-1700 2750);
PAINT SKYBLUE (-1700 2750);
DISPLAY INVISIBLE (-1700 2750);
FORCEPROP 2 LAST ROOM VDDQ_ABC_PWR_VR
J 0
(-1700 3000);
PAINT MONO (-1700 3000);
DISPLAY INVISIBLE (-1700 3000);
FORCEPROP 2 LAST BOM_COST MEM_VRD_PVDDQ_CD
J 0
(-1700 3000);
PAINT MONO (-1700 3000);
DISPLAY INVISIBLE (-1700 3000);
FORCEPROP 2 LAST CDS_LIB mstr_discrete
J 0
(-1750 2850);
DISPLAY INVISIBLE (-1750 2850);
FORCEPROP 1 LAST PATH I328
J 0
(-1700 3000);
DISPLAY 0.978723 (-1700 3000);
PAINT WHITE (-1700 3000);
DISPLAY INVISIBLE (-1700 3000);
FORCEPROP 2 LAST SEC 1
J 0
(-1700 3050);
DISPLAY 0.680851 (-1700 3050);
PAINT MONO (-1700 3050);
DISPLAY INVISIBLE (-1700 3050);
FORCEPROP 2 LAST SEC_TYPE 0805
J 0
(-1700 3050);
DISPLAY 1.021277 (-1700 3050);
PAINT ORANGE (-1700 3050);
DISPLAY INVISIBLE (-1700 3050);
FORCEADD CAP..1
(2875 2850);
FORCEPROP 1 LASTPIN (2875 2950) $PN 1
J 0
(2885 2930);
DISPLAY 0.617021 (2885 2930);
PAINT ORANGE (2885 2930);
FORCEPROP 0 LAST NEW_MATERIAL X6S
J 0
(2925 2600);
DISPLAY 0.638298 (2925 2600);
PAINT BROWN (2925 2600);
DISPLAY BOTH (2925 2600);
FORCEPROP 0 LAST BOM_SS NOPOP
J 0
(2925 2550);
DISPLAY 0.638298 (2925 2550);
PAINT BROWN (2925 2550);
DISPLAY BOTH (2925 2550);
FORCEPROP 0 LAST GROUP PWR_MLCC_CAP
J 0
(2931 2512);
DISPLAY 0.638298 (2931 2512);
PAINT BROWN (2931 2512);
DISPLAY BOTH (2931 2512);
FORCEPROP 1 LAST PACK_TYPE 0805
J 0
(2925 2700);
DISPLAY 0.617021 (2925 2700);
PAINT SKYBLUE (2925 2700);
FORCEPROP 1 LASTPIN (2875 2750) $PN 2
J 0
(2885 2730);
DISPLAY 0.617021 (2885 2730);
PAINT ORANGE (2885 2730);
FORCEPROP 1 LAST PART_NUMBER 602433-112
J 0
(2925 2750);
DISPLAY 0.617021 (2925 2750);
PAINT BLUE (2925 2750);
FORCEPROP 1 LAST TOLERANCE 20%
J 0
(2925 2800);
DISPLAY 0.617021 (2925 2800);
PAINT SKYBLUE (2925 2800);
FORCEPROP 1 LAST VOLTAGE 4V
J 0
(2925 2850);
DISPLAY 0.617021 (2925 2850);
PAINT SKYBLUE (2925 2850);
FORCEPROP 1 LAST VALUE 100UF
J 0
(2925 2900);
DISPLAY 0.617021 (2925 2900);
PAINT SKYBLUE (2925 2900);
FORCEPROP 1 LAST LOCATION C5G20
J 0
(2925 2950);
DISPLAY 0.617021 (2925 2950);
PAINT AQUA (2925 2950);
FORCEPROP 0 LAST NEW_PN 078.1071T.M002
J 0
(2927 2636);
DISPLAY 0.638298 (2927 2636);
PAINT BROWN (2927 2636);
DISPLAY BOTH (2927 2636);
FORCEPROP 1 LAST MATERIAL X5R
J 0
(2925 2750);
DISPLAY 0.617021 (2925 2750);
PAINT SKYBLUE (2925 2750);
DISPLAY INVISIBLE (2925 2750);
FORCEPROP 2 LAST SEC 1
J 0
(2925 3050);
DISPLAY 0.680851 (2925 3050);
PAINT MONO (2925 3050);
DISPLAY INVISIBLE (2925 3050);
FORCEPROP 2 LAST SEC_TYPE 0805
J 0
(2925 3050);
DISPLAY 1.021277 (2925 3050);
PAINT ORANGE (2925 3050);
DISPLAY INVISIBLE (2925 3050);
FORCEPROP 2 LAST ROOM VDDQ_ABC_PWR_VR
J 0
(2925 3000);
PAINT MONO (2925 3000);
DISPLAY INVISIBLE (2925 3000);
FORCEPROP 2 LAST BOM_COST MEM_VRD_PVDDQ_CD
J 0
(2925 3000);
PAINT MONO (2925 3000);
DISPLAY INVISIBLE (2925 3000);
FORCEPROP 2 LAST CDS_LIB mstr_discrete
J 0
(2875 2850);
PAINT MONO (2875 2850);
DISPLAY INVISIBLE (2875 2850);
FORCEPROP 0 LAST CDS_SEC 1
J 0
(2925 3000);
PAINT MONO (2925 3000);
DISPLAY INVISIBLE (2925 3000);
FORCEPROP 1 LAST PATH I329
J 0
(2925 3000);
DISPLAY 0.978723 (2925 3000);
PAINT WHITE (2925 3000);
DISPLAY INVISIBLE (2925 3000);
FORCEPROP 2 LAST CDS_LOCATION C5G20
J 0
(2925 2950);
DISPLAY 0.617021 (2925 2950);
PAINT AQUA (2925 2950);
DISPLAY INVISIBLE (2925 2950);
FORCEADD RES..2
(4550 -400);
FORCEPROP 1 LAST PACK_TYPE 0603
J 0
(4590 -550);
DISPLAY 0.617021 (4590 -550);
PAINT SKYBLUE (4590 -550);
FORCEPROP 1 LAST MATERIAL CHIP
J 0
(4590 -450);
DISPLAY 0.617021 (4590 -450);
PAINT SKYBLUE (4590 -450);
FORCEPROP 1 LAST WATTAGE 1/10W
J 0
(4590 -400);
DISPLAY 0.617021 (4590 -400);
PAINT SKYBLUE (4590 -400);
FORCEPROP 1 LAST TOLERANCE 1%
J 0
(4595 -350);
DISPLAY 0.617021 (4595 -350);
PAINT SKYBLUE (4595 -350);
FORCEPROP 1 LAST VALUE 120.0
J 0
(4595 -300);
DISPLAY 0.617021 (4595 -300);
PAINT SKYBLUE (4595 -300);
FORCEPROP 1 LAST LOCATION R3U4
J 0
(4595 -250);
DISPLAY 0.617021 (4595 -250);
PAINT AQUA (4595 -250);
FORCEPROP 1 LASTPIN (4550 -300) $PN 1
J 0
(4555 -338);
DISPLAY 0.617021 (4555 -338);
PAINT GREEN (4555 -338);
FORCEPROP 1 LASTPIN (4550 -500) $PN 2
J 0
(4555 -490);
DISPLAY 0.617021 (4555 -490);
PAINT GREEN (4555 -490);
FORCEPROP 1 LAST PART_NUMBER G22026-003
J 0
(4590 -500);
DISPLAY 0.617021 (4590 -500);
PAINT BLUE (4590 -500);
FORCEPROP 2 LAST CDS_SEC 1
J 0
(4600 -175);
PAINT MONO (4600 -175);
DISPLAY INVISIBLE (4600 -175);
FORCEPROP 2 LAST $SEC 1
J 0
(4600 -175);
PAINT MONO (4600 -175);
DISPLAY INVISIBLE (4600 -175);
FORCEPROP 2 LAST CDS_LOCATION R3U4
J 0
(4595 -275);
DISPLAY 0.617021 (4595 -275);
PAINT AQUA (4595 -275);
DISPLAY INVISIBLE (4595 -275);
FORCEPROP 2 LAST BOM_COST MEM_VRD_PVPP_AB
J 0
(4600 -225);
PAINT MONO (4600 -225);
DISPLAY INVISIBLE (4600 -225);
FORCEPROP 1 LAST PATH I58
J 0
(4600 -225);
DISPLAY 0.978723 (4600 -225);
PAINT GREEN (4600 -225);
DISPLAY INVISIBLE (4600 -225);
FORCEPROP 2 LAST ROOM VDDQ_ABC_PWR_VR
J 0
(4600 -225);
PAINT MONO (4600 -225);
DISPLAY INVISIBLE (4600 -225);
FORCEPROP 2 LAST CDS_LIB mstr_discrete
J 0
(4550 -400);
PAINT ORANGE (4550 -400);
DISPLAY INVISIBLE (4550 -400);
FORCEADD GND..1
(400 1275);
FORCEPROP 3 LASTPIN (400 1325) SIG_NAME GND\g
J 0
(410 1335);
DISPLAY 0.659574 (410 1335);
PAINT MONO (410 1335);
DISPLAY INVISIBLE (410 1335);
FORCEPROP 2 LAST ROOM VDDQ_ABC_PWR_VR
J 0
(-150 1350);
PAINT ORANGE (-150 1350);
DISPLAY INVISIBLE (-150 1350);
FORCEPROP 2 LAST BOM_COST MEM_VRD_PVPP_AB
J 0
(75 1350);
PAINT MONO (75 1350);
DISPLAY INVISIBLE (75 1350);
FORCEPROP 1 LAST SIZE 1B
J 0
(475 1225);
DISPLAY 0.893617 (475 1225);
PAINT GREEN (475 1225);
DISPLAY INVISIBLE (475 1225);
FORCEPROP 2 LAST CDS_LIB mstr_symbols
J 0
(400 1275);
PAINT ORANGE (400 1275);
DISPLAY INVISIBLE (400 1275);
FORCEPROP 1 LAST PATH I65
J 0
(475 1275);
DISPLAY 1.170213 (475 1275);
PAINT AQUA (475 1275);
DISPLAY INVISIBLE (475 1275);
FORCEPROP 1 LAST VOLTAGE 0
J 0
(400 1275);
PAINT SKYBLUE (400 1275);
DISPLAY INVISIBLE (400 1275);
FORCEPROP 1 LAST BODY_TYPE PLUMBING
J 0
(355 1232);
DISPLAY 0.340426 (355 1232);
PAINT GREEN (355 1232);
DISPLAY INVISIBLE (355 1232);
FORCEPROP 1 LAST HDL_POWER GND
J 0
(400 1425);
DISPLAY 0.893617 (400 1425);
PAINT GREEN (400 1425);
DISPLAY INVISIBLE (400 1425);
FORCEADD OFFPAGE..1
(-1525 1675);
FORCEPROP 2 LAST $XR0 215 
J 0
(-1777 1675);
DISPLAY 0.638298 (-1777 1675);
PAINT MONO (-1777 1675);
FORCEPROP 2 LAST PATH I70
J 0
(-1455 1745);
DISPLAY 1.361702 (-1455 1745);
PAINT ORANGE (-1455 1745);
DISPLAY INVISIBLE (-1455 1745);
FORCEPROP 2 LAST CDS_LIB mstr_standard
J 0
(-1525 1675);
PAINT ORANGE (-1525 1675);
DISPLAY INVISIBLE (-1525 1675);
FORCEPROP 1 LAST OFFPAGE TRUE
J 0
(-1200 1550);
DISPLAY 0.893617 (-1200 1550);
PAINT GREEN (-1200 1550);
DISPLAY INVISIBLE (-1200 1550);
FORCEPROP 1 LAST COMMENT_BODY TRUE
J 0
(-1400 1575);
DISPLAY 0.893617 (-1400 1575);
PAINT GREEN (-1400 1575);
DISPLAY INVISIBLE (-1400 1575);
FORCEADD OFFPAGE..1
(-1525 1925);
FORCEPROP 2 LAST $XR0 215 
J 0
(-1777 1925);
DISPLAY 0.638298 (-1777 1925);
PAINT MONO (-1777 1925);
FORCEPROP 2 LAST CDS_LIB mstr_standard
J 0
(-1525 1925);
PAINT ORANGE (-1525 1925);
DISPLAY INVISIBLE (-1525 1925);
FORCEPROP 2 LAST PATH I72
J 0
(-1475 2000);
DISPLAY 1.361702 (-1475 2000);
PAINT ORANGE (-1475 2000);
DISPLAY INVISIBLE (-1475 2000);
FORCEPROP 1 LAST OFFPAGE TRUE
J 0
(-1200 1800);
DISPLAY 1.170213 (-1200 1800);
PAINT GREEN (-1200 1800);
DISPLAY INVISIBLE (-1200 1800);
FORCEPROP 1 LAST COMMENT_BODY TRUE
J 0
(-1400 1825);
DISPLAY 1.170213 (-1400 1825);
PAINT GREEN (-1400 1825);
DISPLAY INVISIBLE (-1400 1825);
FORCEADD PVDDQ_ABC..1
(425 2150);
FORCEPROP 3 LASTPIN (425 2100) SIG_NAME PVDDQ_ABC\g
J 0
(435 2110);
DISPLAY 0.659574 (435 2110);
PAINT MONO (435 2110);
DISPLAY INVISIBLE (435 2110);
FORCEPROP 2 LAST BOM_COST MEM_VRD_PVPP_AB
J 0
(450 2250);
PAINT MONO (450 2250);
DISPLAY INVISIBLE (450 2250);
FORCEPROP 2 LAST CDS_LIB mstr_symbols
J 0
(425 2150);
PAINT ORANGE (425 2150);
DISPLAY INVISIBLE (425 2150);
FORCEPROP 1 LAST PATH I73
J 0
(475 2175);
DISPLAY 0.872340 (475 2175);
PAINT AQUA (475 2175);
DISPLAY INVISIBLE (475 2175);
FORCEPROP 1 LAST VOLTAGE 1.2V
J 0
(380 2107);
DISPLAY 0.340426 (380 2107);
PAINT SKYBLUE (380 2107);
DISPLAY INVISIBLE (380 2107);
FORCEPROP 2 LAST ROOM VDDQ_ABC_PWR_VR
J 0
(675 2250);
PAINT ORANGE (675 2250);
DISPLAY INVISIBLE (675 2250);
FORCEPROP 1 LAST BODY_TYPE PLUMBING
J 0
(380 2107);
DISPLAY 0.340426 (380 2107);
PAINT GREEN (380 2107);
DISPLAY INVISIBLE (380 2107);
FORCEPROP 1 LAST HDL_POWER PVDDQ_ABC
J 1
(425 2200);
DISPLAY 0.872340 (425 2200);
PAINT GREEN (425 2200);
DISPLAY INVISIBLE (425 2200);
FORCEADD RES..2
(-250 1700);
FORCEPROP 1 LASTPIN (-250 1600) $PN 2
J 0
(-245 1610);
DISPLAY 0.617021 (-245 1610);
PAINT ORANGE (-245 1610);
FORCEPROP 1 LASTPIN (-250 1800) $PN 1
J 0
(-245 1762);
DISPLAY 0.617021 (-245 1762);
PAINT ORANGE (-245 1762);
FORCEPROP 1 LAST TOLERANCE 1%
J 0
(-205 1725);
DISPLAY 0.617021 (-205 1725);
PAINT SKYBLUE (-205 1725);
FORCEPROP 1 LAST VALUE 100.0
J 0
(-205 1775);
DISPLAY 0.617021 (-205 1775);
PAINT SKYBLUE (-205 1775);
FORCEPROP 1 LAST LOCATION R4U6
J 0
(-205 1825);
DISPLAY 0.617021 (-205 1825);
PAINT AQUA (-205 1825);
FORCEPROP 1 LAST WATTAGE 1/16W
J 0
(-210 1675);
DISPLAY 0.617021 (-210 1675);
PAINT SKYBLUE (-210 1675);
FORCEPROP 1 LAST MATERIAL EMPTY
J 0
(-210 1625);
DISPLAY 0.617021 (-210 1625);
PAINT RED (-210 1625);
FORCEPROP 1 LAST PACK_TYPE 0402
J 0
(-210 1525);
DISPLAY 0.617021 (-210 1525);
PAINT SKYBLUE (-210 1525);
FORCEPROP 1 LAST PART_NUMBER G21796-017
J 0
(-210 1575);
DISPLAY 0.617021 (-210 1575);
PAINT BLUE (-210 1575);
FORCEPROP 2 LAST CDS_LIB mstr_discrete
J 0
(-250 1700);
PAINT ORANGE (-250 1700);
DISPLAY INVISIBLE (-250 1700);
FORCEPROP 2 LAST SEC_TYPE 0402
J 0
(-200 1950);
DISPLAY 1.021277 (-200 1950);
PAINT ORANGE (-200 1950);
DISPLAY INVISIBLE (-200 1950);
FORCEPROP 2 LAST SEC 1
J 0
(-200 1950);
DISPLAY 0.680851 (-200 1950);
PAINT MONO (-200 1950);
DISPLAY INVISIBLE (-200 1950);
FORCEPROP 2 LAST CDS_LOCATION R4U6
J 0
(-205 1825);
DISPLAY 0.617021 (-205 1825);
PAINT AQUA (-205 1825);
DISPLAY INVISIBLE (-205 1825);
FORCEPROP 1 LAST PATH I74
J 0
(-200 1875);
DISPLAY 1.319149 (-200 1875);
PAINT WHITE (-200 1875);
DISPLAY INVISIBLE (-200 1875);
FORCEPROP 0 LAST ROOM VDDQ_ABC_PWR_VR
J 0
(-200 1925);
DISPLAY 1.021277 (-200 1925);
PAINT ORANGE (-200 1925);
DISPLAY INVISIBLE (-200 1925);
FORCEADD CAPP..1
(3350 -400);
FORCEPROP 1 LAST VOLTAGE 2.5V
J 0
(3400 -400);
DISPLAY 0.617021 (3400 -400);
PAINT SKYBLUE (3400 -400);
FORCEPROP 1 LAST TOLERANCE 20%
J 0
(3400 -350);
DISPLAY 0.617021 (3400 -350);
PAINT SKYBLUE (3400 -350);
FORCEPROP 0 LAST GROUP PWR_BULK_CAP
J 0
(3415 -599);
DISPLAY 0.638298 (3415 -599);
PAINT BROWN (3415 -599);
DISPLAY BOTH (3415 -599);
FORCEPROP 1 LAST PART_NUMBER 699013-049
J 0
(3400 -550);
DISPLAY 0.617021 (3400 -550);
PAINT BLUE (3400 -550);
FORCEPROP 1 LAST PACK_TYPE 3018
J 0
(3400 -500);
DISPLAY 0.617021 (3400 -500);
PAINT SKYBLUE (3400 -500);
FORCEPROP 1 LAST MATERIAL ALUM
J 0
(3400 -450);
DISPLAY 0.617021 (3400 -450);
PAINT SKYBLUE (3400 -450);
FORCEPROP 1 LAST VALUE 470UF
J 0
(3400 -300);
DISPLAY 0.617021 (3400 -300);
PAINT SKYBLUE (3400 -300);
FORCEPROP 1 LAST LOCATION C7G28
J 0
(3400 -250);
DISPLAY 0.617021 (3400 -250);
PAINT AQUA (3400 -250);
FORCEPROP 1 LASTPIN (3350 -300) $PN 1
J 0
(3360 -315);
DISPLAY 0.617021 (3360 -315);
PAINT ORANGE (3360 -315);
FORCEPROP 1 LASTPIN (3350 -500) $PN 2
J 0
(3360 -515);
DISPLAY 0.617021 (3360 -515);
PAINT ORANGE (3360 -515);
FORCEPROP 2 LAST SEC 1
J 0
(3400 -175);
DISPLAY 0.680851 (3400 -175);
PAINT MONO (3400 -175);
DISPLAY INVISIBLE (3400 -175);
FORCEPROP 2 LAST SEC_TYPE 3018
J 0
(3400 -175);
DISPLAY 1.021277 (3400 -175);
PAINT ORANGE (3400 -175);
DISPLAY INVISIBLE (3400 -175);
FORCEPROP 1 LAST PATH I75
J 0
(3400 -250);
DISPLAY 1.319149 (3400 -250);
PAINT ORANGE (3400 -250);
DISPLAY INVISIBLE (3400 -250);
FORCEPROP 0 LAST ROOM VDDQ_ABC_PWR_VR
J 0
(3400 -250);
DISPLAY 1.021277 (3400 -250);
PAINT ORANGE (3400 -250);
DISPLAY INVISIBLE (3400 -250);
FORCEPROP 2 LAST CDS_LOCATION C7G28
J 0
(3400 -300);
DISPLAY 0.617021 (3400 -300);
PAINT AQUA (3400 -300);
DISPLAY INVISIBLE (3400 -300);
FORCEPROP 2 LAST CDS_LIB mstr_discrete
J 0
(3350 -400);
PAINT ORANGE (3350 -400);
DISPLAY INVISIBLE (3350 -400);
FORCEADD CAPP..1
(3650 -400);
FORCEPROP 0 LAST GROUP PWR_BULK_CAP
J 0
(3715 -649);
DISPLAY 0.638298 (3715 -649);
PAINT BROWN (3715 -649);
DISPLAY BOTH (3715 -649);
FORCEPROP 1 LAST VALUE 470UF
J 0
(3700 -300);
DISPLAY 0.617021 (3700 -300);
PAINT SKYBLUE (3700 -300);
FORCEPROP 1 LAST TOLERANCE 20%
J 0
(3700 -350);
DISPLAY 0.617021 (3700 -350);
PAINT SKYBLUE (3700 -350);
FORCEPROP 1 LAST VOLTAGE 2.5V
J 0
(3700 -400);
DISPLAY 0.617021 (3700 -400);
PAINT SKYBLUE (3700 -400);
FORCEPROP 1 LASTPIN (3650 -300) $PN 1
J 0
(3660 -315);
DISPLAY 0.617021 (3660 -315);
PAINT ORANGE (3660 -315);
FORCEPROP 1 LASTPIN (3650 -500) $PN 2
J 0
(3660 -515);
DISPLAY 0.617021 (3660 -515);
PAINT ORANGE (3660 -515);
FORCEPROP 1 LAST PACK_TYPE 3018
J 0
(3700 -500);
DISPLAY 0.617021 (3700 -500);
PAINT SKYBLUE (3700 -500);
FORCEPROP 1 LAST PART_NUMBER 699013-049
J 0
(3700 -550);
DISPLAY 0.617021 (3700 -550);
PAINT BLUE (3700 -550);
FORCEPROP 1 LAST MATERIAL ALUM
J 0
(3700 -450);
DISPLAY 0.617021 (3700 -450);
PAINT SKYBLUE (3700 -450);
FORCEPROP 1 LAST LOCATION C3U1
J 0
(3700 -250);
DISPLAY 0.617021 (3700 -250);
PAINT AQUA (3700 -250);
FORCEPROP 2 LAST CDS_LIB mstr_discrete
J 0
(3650 -400);
PAINT ORANGE (3650 -400);
DISPLAY INVISIBLE (3650 -400);
FORCEPROP 2 LAST SEC_TYPE 3018
J 0
(3700 -175);
DISPLAY 1.021277 (3700 -175);
PAINT ORANGE (3700 -175);
DISPLAY INVISIBLE (3700 -175);
FORCEPROP 2 LAST SEC 1
J 0
(3700 -175);
DISPLAY 0.680851 (3700 -175);
PAINT MONO (3700 -175);
DISPLAY INVISIBLE (3700 -175);
FORCEPROP 2 LAST CDS_LOCATION C3U1
J 0
(3700 -300);
DISPLAY 0.617021 (3700 -300);
PAINT AQUA (3700 -300);
DISPLAY INVISIBLE (3700 -300);
FORCEPROP 1 LAST PATH I76
J 0
(3700 -250);
DISPLAY 1.319149 (3700 -250);
PAINT ORANGE (3700 -250);
DISPLAY INVISIBLE (3700 -250);
FORCEPROP 0 LAST ROOM VDDQ_ABC_PWR_VR
J 0
(3700 -250);
DISPLAY 1.021277 (3700 -250);
PAINT ORANGE (3700 -250);
DISPLAY INVISIBLE (3700 -250);
FORCEADD CAPP..1
(3950 -400);
FORCEPROP 0 LAST GROUP PWR_BULK_CAP
J 0
(4015 -599);
DISPLAY 0.638298 (4015 -599);
PAINT BROWN (4015 -599);
DISPLAY BOTH (4015 -599);
FORCEPROP 1 LAST PART_NUMBER 699013-049
J 0
(4000 -550);
DISPLAY 0.617021 (4000 -550);
PAINT BLUE (4000 -550);
FORCEPROP 1 LAST LOCATION C3U5
J 0
(4000 -250);
DISPLAY 0.617021 (4000 -250);
PAINT AQUA (4000 -250);
FORCEPROP 1 LAST VALUE 470UF
J 0
(4000 -300);
DISPLAY 0.617021 (4000 -300);
PAINT SKYBLUE (4000 -300);
FORCEPROP 1 LAST TOLERANCE 20%
J 0
(4000 -350);
DISPLAY 0.617021 (4000 -350);
PAINT SKYBLUE (4000 -350);
FORCEPROP 1 LAST VOLTAGE 2.5V
J 0
(4000 -400);
DISPLAY 0.617021 (4000 -400);
PAINT SKYBLUE (4000 -400);
FORCEPROP 1 LAST MATERIAL ALUM
J 0
(4000 -450);
DISPLAY 0.617021 (4000 -450);
PAINT SKYBLUE (4000 -450);
FORCEPROP 1 LAST PACK_TYPE 3018
J 0
(4000 -500);
DISPLAY 0.617021 (4000 -500);
PAINT SKYBLUE (4000 -500);
FORCEPROP 1 LASTPIN (3950 -300) $PN 1
J 0
(3960 -315);
DISPLAY 0.617021 (3960 -315);
PAINT ORANGE (3960 -315);
FORCEPROP 1 LASTPIN (3950 -500) $PN 2
J 0
(3960 -515);
DISPLAY 0.617021 (3960 -515);
PAINT ORANGE (3960 -515);
FORCEPROP 2 LAST SEC 1
J 0
(4000 -175);
DISPLAY 0.680851 (4000 -175);
PAINT MONO (4000 -175);
DISPLAY INVISIBLE (4000 -175);
FORCEPROP 2 LAST SEC_TYPE 3018
J 0
(4000 -175);
DISPLAY 1.021277 (4000 -175);
PAINT ORANGE (4000 -175);
DISPLAY INVISIBLE (4000 -175);
FORCEPROP 1 LAST PATH I77
J 0
(4000 -250);
DISPLAY 1.319149 (4000 -250);
PAINT ORANGE (4000 -250);
DISPLAY INVISIBLE (4000 -250);
FORCEPROP 2 LAST CDS_LOCATION C3U5
J 0
(4000 -300);
DISPLAY 0.617021 (4000 -300);
PAINT AQUA (4000 -300);
DISPLAY INVISIBLE (4000 -300);
FORCEPROP 0 LAST ROOM VDDQ_ABC_PWR_VR
J 0
(4000 -250);
DISPLAY 1.021277 (4000 -250);
PAINT ORANGE (4000 -250);
DISPLAY INVISIBLE (4000 -250);
FORCEPROP 2 LAST CDS_LIB mstr_discrete
J 0
(3950 -400);
PAINT ORANGE (3950 -400);
DISPLAY INVISIBLE (3950 -400);
FORCEADD CAPP..1
(4250 -400);
FORCEPROP 1 LASTPIN (4250 -500) $PN 2
J 0
(4260 -515);
DISPLAY 0.617021 (4260 -515);
PAINT ORANGE (4260 -515);
FORCEPROP 1 LAST PACK_TYPE 3018
J 0
(4300 -500);
DISPLAY 0.617021 (4300 -500);
PAINT SKYBLUE (4300 -500);
FORCEPROP 1 LAST LOCATION C3U8
J 0
(4300 -250);
DISPLAY 0.617021 (4300 -250);
PAINT AQUA (4300 -250);
FORCEPROP 1 LAST VALUE 470UF
J 0
(4300 -300);
DISPLAY 0.617021 (4300 -300);
PAINT SKYBLUE (4300 -300);
FORCEPROP 1 LASTPIN (4250 -300) $PN 1
J 0
(4260 -315);
DISPLAY 0.617021 (4260 -315);
PAINT ORANGE (4260 -315);
FORCEPROP 0 LAST GROUP PWR_BULK_CAP
J 0
(4315 -649);
DISPLAY 0.638298 (4315 -649);
PAINT BROWN (4315 -649);
DISPLAY BOTH (4315 -649);
FORCEPROP 1 LAST TOLERANCE 20%
J 0
(4300 -350);
DISPLAY 0.617021 (4300 -350);
PAINT SKYBLUE (4300 -350);
FORCEPROP 1 LAST VOLTAGE 2.5V
J 0
(4300 -400);
DISPLAY 0.617021 (4300 -400);
PAINT SKYBLUE (4300 -400);
FORCEPROP 1 LAST MATERIAL ALUM
J 0
(4300 -450);
DISPLAY 0.617021 (4300 -450);
PAINT SKYBLUE (4300 -450);
FORCEPROP 1 LAST PART_NUMBER 699013-049
J 0
(4300 -550);
DISPLAY 0.617021 (4300 -550);
PAINT BLUE (4300 -550);
FORCEPROP 2 LAST CDS_LIB mstr_discrete
J 0
(4250 -400);
PAINT ORANGE (4250 -400);
DISPLAY INVISIBLE (4250 -400);
FORCEPROP 2 LAST CDS_LOCATION C3U8
J 0
(4300 -300);
DISPLAY 0.617021 (4300 -300);
PAINT AQUA (4300 -300);
DISPLAY INVISIBLE (4300 -300);
FORCEPROP 1 LAST PATH I78
J 0
(4300 -250);
DISPLAY 1.319149 (4300 -250);
PAINT ORANGE (4300 -250);
DISPLAY INVISIBLE (4300 -250);
FORCEPROP 0 LAST ROOM VDDQ_ABC_PWR_VR
J 0
(4300 -250);
DISPLAY 1.021277 (4300 -250);
PAINT ORANGE (4300 -250);
DISPLAY INVISIBLE (4300 -250);
FORCEPROP 2 LAST SEC_TYPE 3018
J 0
(4300 -175);
DISPLAY 1.021277 (4300 -175);
PAINT ORANGE (4300 -175);
DISPLAY INVISIBLE (4300 -175);
FORCEPROP 2 LAST SEC 1
J 0
(4300 -175);
DISPLAY 0.680851 (4300 -175);
PAINT MONO (4300 -175);
DISPLAY INVISIBLE (4300 -175);
FORCEADD PVDDQ_ABC..1
(3350 -100);
FORCEPROP 3 LASTPIN (3350 -150) SIG_NAME PVDDQ_ABC\g
J 0
(3360 -140);
DISPLAY 0.659574 (3360 -140);
PAINT MONO (3360 -140);
DISPLAY INVISIBLE (3360 -140);
FORCEPROP 1 LAST HDL_POWER PVDDQ_ABC
J 1
(3350 -50);
DISPLAY 0.872340 (3350 -50);
PAINT GREEN (3350 -50);
DISPLAY INVISIBLE (3350 -50);
FORCEPROP 1 LAST BODY_TYPE PLUMBING
J 0
(3305 -143);
DISPLAY 0.340426 (3305 -143);
PAINT GREEN (3305 -143);
DISPLAY INVISIBLE (3305 -143);
FORCEPROP 2 LAST ROOM VDDQ_ABC_PWR_VR
J 0
(3575 0);
PAINT ORANGE (3575 0);
DISPLAY INVISIBLE (3575 0);
FORCEPROP 1 LAST VOLTAGE 1.2V
J 0
(3305 -143);
DISPLAY 0.340426 (3305 -143);
PAINT SKYBLUE (3305 -143);
DISPLAY INVISIBLE (3305 -143);
FORCEPROP 1 LAST PATH I80
J 0
(3400 -75);
DISPLAY 0.872340 (3400 -75);
PAINT AQUA (3400 -75);
DISPLAY INVISIBLE (3400 -75);
FORCEPROP 2 LAST CDS_LIB mstr_symbols
J 0
(3350 -100);
PAINT ORANGE (3350 -100);
DISPLAY INVISIBLE (3350 -100);
FORCEPROP 2 LAST BOM_COST MEM_VRD_PVPP_AB
J 0
(3400 0);
PAINT MONO (3400 0);
DISPLAY INVISIBLE (3400 0);
FORCEADD GND..1
(3350 -775);
FORCEPROP 3 LASTPIN (3350 -725) SIG_NAME GND\g
J 0
(3360 -715);
DISPLAY 0.659574 (3360 -715);
PAINT MONO (3360 -715);
DISPLAY INVISIBLE (3360 -715);
FORCEPROP 1 LAST HDL_POWER GND
J 0
(3350 -625);
DISPLAY 0.893617 (3350 -625);
PAINT GREEN (3350 -625);
DISPLAY INVISIBLE (3350 -625);
FORCEPROP 1 LAST BODY_TYPE PLUMBING
J 0
(3305 -818);
DISPLAY 0.340426 (3305 -818);
PAINT GREEN (3305 -818);
DISPLAY INVISIBLE (3305 -818);
FORCEPROP 1 LAST VOLTAGE 0
J 0
(3350 -775);
PAINT SKYBLUE (3350 -775);
DISPLAY INVISIBLE (3350 -775);
FORCEPROP 1 LAST PATH I81
J 0
(3425 -775);
DISPLAY 1.170213 (3425 -775);
PAINT AQUA (3425 -775);
DISPLAY INVISIBLE (3425 -775);
FORCEPROP 1 LAST SIZE 1B
J 0
(3425 -825);
DISPLAY 0.893617 (3425 -825);
PAINT GREEN (3425 -825);
DISPLAY INVISIBLE (3425 -825);
FORCEPROP 2 LAST CDS_LIB mstr_symbols
J 0
(3350 -775);
PAINT ORANGE (3350 -775);
DISPLAY INVISIBLE (3350 -775);
FORCEPROP 2 LAST BOM_COST MEM_VRD_PVPP_AB
J 0
(3025 -700);
PAINT MONO (3025 -700);
DISPLAY INVISIBLE (3025 -700);
FORCEPROP 2 LAST ROOM VDDQ_ABC_PWR_VR
J 0
(2800 -700);
PAINT ORANGE (2800 -700);
DISPLAY INVISIBLE (2800 -700);
FORCEADD PVDDQ_ABC..1
(2875 3125);
FORCEPROP 3 LASTPIN (2875 3075) SIG_NAME PVDDQ_ABC\g
J 0
(2885 3085);
DISPLAY 0.659574 (2885 3085);
PAINT MONO (2885 3085);
DISPLAY INVISIBLE (2885 3085);
FORCEPROP 2 LAST BOM_COST MEM_VRD_PVDDQ_CD
J 0
(2950 3225);
PAINT MONO (2950 3225);
DISPLAY INVISIBLE (2950 3225);
FORCEPROP 2 LAST CDS_LIB mstr_symbols
J 0
(2875 3125);
PAINT ORANGE (2875 3125);
DISPLAY INVISIBLE (2875 3125);
FORCEPROP 1 LAST PATH I93
J 0
(2925 3150);
DISPLAY 0.872340 (2925 3150);
PAINT AQUA (2925 3150);
DISPLAY INVISIBLE (2925 3150);
FORCEPROP 1 LAST VOLTAGE 1.2V
J 0
(2830 3082);
DISPLAY 0.340426 (2830 3082);
PAINT SKYBLUE (2830 3082);
DISPLAY INVISIBLE (2830 3082);
FORCEPROP 2 LAST ROOM VDDQ_ABC_PWR_VR
J 0
(3125 3225);
PAINT ORANGE (3125 3225);
DISPLAY INVISIBLE (3125 3225);
FORCEPROP 1 LAST BODY_TYPE PLUMBING
J 0
(2830 3082);
DISPLAY 0.340426 (2830 3082);
PAINT GREEN (2830 3082);
DISPLAY INVISIBLE (2830 3082);
FORCEPROP 1 LAST HDL_POWER PVDDQ_ABC
J 1
(2875 3175);
DISPLAY 0.872340 (2875 3175);
PAINT GREEN (2875 3175);
DISPLAY INVISIBLE (2875 3175);
FORCEADD GND..1
(2875 2400);
FORCEPROP 3 LASTPIN (2875 2450) SIG_NAME GND\g
J 0
(2885 2460);
DISPLAY 0.659574 (2885 2460);
PAINT MONO (2885 2460);
DISPLAY INVISIBLE (2885 2460);
FORCEPROP 1 LAST PATH I94
J 0
(2950 2400);
DISPLAY 1.170213 (2950 2400);
PAINT AQUA (2950 2400);
DISPLAY INVISIBLE (2950 2400);
FORCEPROP 1 LAST SIZE 1B
J 0
(2950 2350);
DISPLAY 0.893617 (2950 2350);
PAINT GREEN (2950 2350);
DISPLAY INVISIBLE (2950 2350);
FORCEPROP 2 LAST BOM_COST MEM_VRD_PVDDQ_CD
J 0
(2550 2475);
PAINT MONO (2550 2475);
DISPLAY INVISIBLE (2550 2475);
FORCEPROP 1 LAST VOLTAGE 0
J 0
(2875 2400);
PAINT SKYBLUE (2875 2400);
DISPLAY INVISIBLE (2875 2400);
FORCEPROP 2 LAST CDS_LIB mstr_symbols
J 0
(2875 2400);
PAINT ORANGE (2875 2400);
DISPLAY INVISIBLE (2875 2400);
FORCEPROP 2 LAST ROOM VDDQ_ABC_PWR_VR
J 0
(2325 2475);
PAINT ORANGE (2325 2475);
DISPLAY INVISIBLE (2325 2475);
FORCEPROP 1 LAST BODY_TYPE PLUMBING
J 0
(2830 2357);
DISPLAY 0.340426 (2830 2357);
PAINT GREEN (2830 2357);
DISPLAY INVISIBLE (2830 2357);
FORCEPROP 1 LAST HDL_POWER GND
J 0
(2875 2550);
DISPLAY 0.893617 (2875 2550);
PAINT GREEN (2875 2550);
DISPLAY INVISIBLE (2875 2550);
FORCEADD DNS..2
(-245 1695);
PAINT RED (-245 1695);
FORCEPROP 2 LAST CDS_LIB mstr_misc
J 0
(-245 1695);
PAINT ORANGE (-245 1695);
DISPLAY INVISIBLE (-245 1695);
FORCEPROP 1 LAST COMMENT_BODY TRUE
R 1
J 0
(-170 1470);
DISPLAY 0.872340 (-170 1470);
PAINT GREEN (-170 1470);
DISPLAY INVISIBLE (-170 1470);
FORCEADD DNS..3
(155 1945);
PAINT RED (155 1945);
FORCEPROP 2 LAST CDS_LIB mstr_misc
J 0
(155 1945);
PAINT ORANGE (155 1945);
DISPLAY INVISIBLE (155 1945);
FORCEPROP 1 LAST COMMENT_BODY TRUE
R 1
J 0
(230 1720);
DISPLAY 0.872340 (230 1720);
PAINT GREEN (230 1720);
DISPLAY INVISIBLE (230 1720);
FORCEADD DNS..3
(130 1495);
PAINT RED (130 1495);
FORCEPROP 2 LAST CDS_LIB mstr_misc
J 0
(130 1495);
PAINT ORANGE (130 1495);
DISPLAY INVISIBLE (130 1495);
FORCEPROP 1 LAST COMMENT_BODY TRUE
R 1
J 0
(205 1270);
DISPLAY 0.872340 (205 1270);
PAINT GREEN (205 1270);
DISPLAY INVISIBLE (205 1270);
FORCEADD INTEL_CORP_BPAGE..1
(5975 -1500);
FORCEPROP 1 LAST CDS_CON_LAST_MODIFIED Fri Jun 16 17:49:18 2017
J 0
(4550 -1175);
PAINT GREEN (4550 -1175);
DISPLAY INVISIBLE (4550 -1175);
FORCEPROP 1 LAST CUSTOM_TXT_CDS <CURRENT_DESIGN_SHEET> OF <TOTAL_DESIGN_SHEETS>
J 0
(5475 -1475);
PAINT ORANGE (5475 -1475);
FORCEPROP 2 LAST CUSTOM_TXT_CDS <XR_PAGE_TITLE>
J 0
(-1915 3750);
DISPLAY 0.638298 (-1915 3750);
PAINT PINK (-1915 3750);
DISPLAY INVISIBLE (-1915 3750);
FORCEPROP 2 LAST CUSTOM_TXT_CDS <CON_LAST_MODIFIED>
J 0
(1975 -1400);
PAINT ORANGE (1975 -1400);
FORCEPROP 2 LAST CUSTOM_TXT_CDS <CON_PAGE_NUM> OF <CON_TOTAL_PAGES>
J 0
(5475 -1475);
PAINT GREEN (5475 -1475);
FORCEPROP 1 LAST SCH_TITLE VDDQ ABC DECAP (3 OF 3)
J 0
(-1975 -1450);
DISPLAY 1.212766 (-1975 -1450);
PAINT GREEN (-1975 -1450);
FORCEPROP 2 LAST ROOM VDDQ_ABC_PWR_VR
J 0
(-2125 3600);
PAINT ORANGE (-2125 3600);
DISPLAY INVISIBLE (-2125 3600);
FORCEPROP 2 LAST PAGE_BORDER TRUE
J 0
(-1915 3750);
DISPLAY 0.851064 (-1915 3750);
PAINT PINK (-1915 3750);
DISPLAY INVISIBLE (-1915 3750);
FORCEPROP 2 LAST CDS_LIB mstr_symbols
J 0
(5975 -1500);
PAINT ORANGE (5975 -1500);
DISPLAY INVISIBLE (5975 -1500);
FORCEPROP 1 LAST COMMENT_BODY TRUE
J 0
(5987 -1488);
DISPLAY 0.446809 (5987 -1488);
PAINT GREEN (5987 -1488);
DISPLAY INVISIBLE (5987 -1488);
FORCEPROP 2 LAST CDS_XR_PAGE_TITLE CR-217 : @BASEBOARD_FAB2_LIB.BASEBOARD_FAB2(SCH_1):PAGE217
J 0
(-1915 3750);
DISPLAY 0.638298 (-1915 3750);
PAINT PINK (-1915 3750);
DISPLAY INVISIBLE (-1915 3750);
WIRE 16 -1 (2900 1900)(2900 1950);
WIRE 16 -1 (2900 1900)(3250 1900);
WIRE 16 -1 (2900 1900)(2900 1825);
WIRE 16 -1 (3650 1900)(3250 1900);
WIRE 16 -1 (3250 1825)(3250 1900);
WIRE 16 -1 (4000 1900)(3650 1900);
WIRE 16 -1 (3650 1825)(3650 1900);
WIRE 16 -1 (4350 1900)(4000 1900);
WIRE 16 -1 (4000 1825)(4000 1900);
WIRE 16 -1 (4750 1900)(4350 1900);
WIRE 16 -1 (4350 1825)(4350 1900);
WIRE 16 -1 (4750 1825)(4750 1900);
WIRE 16 -1 (4625 1400)(4625 1475);
WIRE 16 -1 (4625 1475)(4350 1475);
WIRE 16 -1 (4625 1475)(4750 1475);
WIRE 16 -1 (4750 1625)(4750 1475);
WIRE 16 -1 (4000 1475)(4350 1475);
WIRE 16 -1 (4350 1625)(4350 1475);
WIRE 16 -1 (3650 1475)(4000 1475);
WIRE 16 -1 (4000 1625)(4000 1475);
WIRE 16 -1 (3250 1475)(3650 1475);
WIRE 16 -1 (3650 1625)(3650 1475);
WIRE 16 -1 (2900 1475)(3250 1475);
WIRE 16 -1 (3250 1625)(3250 1475);
WIRE 16 -1 (2900 1625)(2900 1475);
WIRE 16 -1 (200 900)(200 1100);
WIRE 16 -1 (200 800)(200 900);
WIRE 16 -1 (-50 900)(200 900);
WIRE 16 -1 (200 600)(200 525);
WIRE 16 -1 (-550 1100)(-550 900);
WIRE 16 -1 (-350 900)(-550 900);
WIRE 16 -1 (150 2575)(150 2600);
WIRE 16 -1 (-200 2600)(150 2600);
WIRE 16 -1 (150 2750)(150 2600);
WIRE 16 -1 (-550 2600)(-200 2600);
WIRE 16 -1 (-200 2750)(-200 2600);
WIRE 16 -1 (-900 2600)(-550 2600);
WIRE 16 -1 (-550 2750)(-550 2600);
WIRE 16 -1 (-900 2750)(-900 2600);
WIRE 16 -1 (-1750 3025)(-1750 3075);
WIRE 16 -1 (-1750 3025)(-1400 3025);
WIRE 16 -1 (-1750 3025)(-1750 2950);
WIRE 16 -1 (-1400 2950)(-1400 3025);
WIRE 16 -1 (2925 1175)(2925 1225);
WIRE 16 -1 (2925 1175)(3275 1175);
WIRE 16 -1 (2925 1175)(2925 1100);
WIRE 16 -1 (3675 1175)(3275 1175);
WIRE 16 -1 (3275 1100)(3275 1175);
WIRE 16 -1 (3675 1100)(3675 1175);
WIRE 16 -1 (3575 675)(3575 750);
WIRE 16 -1 (3275 750)(3575 750);
WIRE 16 -1 (3575 750)(3675 750);
WIRE 16 -1 (3675 900)(3675 750);
WIRE 16 -1 (2925 750)(3275 750);
WIRE 16 -1 (3275 900)(3275 750);
WIRE 16 -1 (2925 900)(2925 750);
WIRE 16 -1 (-900 3025)(-900 3075);
WIRE 16 -1 (-550 3025)(-900 3025);
WIRE 16 -1 (-900 2950)(-900 3025);
WIRE 16 -1 (-200 3025)(-550 3025);
WIRE 16 -1 (-550 2950)(-550 3025);
WIRE 16 -1 (150 3025)(-200 3025);
WIRE 16 -1 (-200 2950)(-200 3025);
WIRE 16 -1 (150 2950)(150 3025);
WIRE 16 -1 (-1400 2550)(-1400 2600);
WIRE 16 -1 (-1750 2600)(-1400 2600);
WIRE 16 -1 (-1400 2750)(-1400 2600);
WIRE 16 -1 (-1750 2750)(-1750 2600);
WIRE 16 -1 (-1825 200)(-1825 250);
WIRE 16 -1 (-1825 200)(-1525 200);
WIRE 16 -1 (-1825 150)(-1825 200);
WIRE 16 -1 (-1525 200)(-1225 200);
WIRE 16 -1 (-1525 150)(-1525 200);
WIRE 16 -1 (-1225 200)(-950 200);
WIRE 16 -1 (-1225 150)(-1225 200);
WIRE 16 -1 (-675 200)(-950 200);
WIRE 16 -1 (-950 150)(-950 200);
WIRE 16 -1 (-375 200)(-675 200);
WIRE 16 -1 (-675 150)(-675 200);
WIRE 16 -1 (-75 200)(-375 200);
WIRE 16 -1 (-375 150)(-375 200);
WIRE 16 -1 (200 200)(-75 200);
WIRE 16 -1 (-75 150)(-75 200);
WIRE 16 -1 (525 200)(200 200);
WIRE 16 -1 (200 150)(200 200);
WIRE 16 -1 (825 200)(525 200);
WIRE 16 -1 (525 150)(525 200);
WIRE 16 -1 (1125 200)(825 200);
WIRE 16 -1 (825 150)(825 200);
WIRE 16 -1 (1400 200)(1125 200);
WIRE 16 -1 (1125 150)(1125 200);
WIRE 16 -1 (1675 200)(1400 200);
WIRE 16 -1 (1400 150)(1400 200);
WIRE 16 -1 (1975 200)(1675 200);
WIRE 16 -1 (1675 150)(1675 200);
WIRE 16 -1 (2275 200)(1975 200);
WIRE 16 -1 (1975 150)(1975 200);
WIRE 16 -1 (2550 200)(2275 200);
WIRE 16 -1 (2275 150)(2275 200);
WIRE 16 -1 (2550 150)(2550 200);
WIRE 16 -1 (-1825 -200)(-1825 -250);
WIRE 16 -1 (-1525 -200)(-1825 -200);
WIRE 16 -1 (-1825 -50)(-1825 -200);
WIRE 16 -1 (-1225 -200)(-1525 -200);
WIRE 16 -1 (-1525 -50)(-1525 -200);
WIRE 16 -1 (-1225 -200)(-950 -200);
WIRE 16 -1 (-1225 -50)(-1225 -200);
WIRE 16 -1 (-675 -200)(-950 -200);
WIRE 16 -1 (-950 -50)(-950 -200);
WIRE 16 -1 (-375 -200)(-675 -200);
WIRE 16 -1 (-675 -50)(-675 -200);
WIRE 16 -1 (-75 -200)(-375 -200);
WIRE 16 -1 (-375 -50)(-375 -200);
WIRE 16 -1 (200 -200)(-75 -200);
WIRE 16 -1 (-75 -50)(-75 -200);
WIRE 16 -1 (525 -200)(200 -200);
WIRE 16 -1 (200 -50)(200 -200);
WIRE 16 -1 (825 -200)(525 -200);
WIRE 16 -1 (525 -50)(525 -200);
WIRE 16 -1 (1125 -200)(825 -200);
WIRE 16 -1 (825 -50)(825 -200);
WIRE 16 -1 (1400 -200)(1125 -200);
WIRE 16 -1 (1125 -50)(1125 -200);
WIRE 16 -1 (1675 -200)(1400 -200);
WIRE 16 -1 (1400 -50)(1400 -200);
WIRE 16 -1 (1975 -200)(1675 -200);
WIRE 16 -1 (1675 -50)(1675 -200);
WIRE 16 -1 (2275 -200)(1975 -200);
WIRE 16 -1 (1975 -50)(1975 -200);
WIRE 16 -1 (2550 -200)(2275 -200);
WIRE 16 -1 (2275 -50)(2275 -200);
WIRE 16 -1 (2550 -50)(2550 -200);
WIRE 16 -1 (-1825 -500)(-1825 -450);
WIRE 16 -1 (-1825 -500)(-1525 -500);
WIRE 16 -1 (-1825 -550)(-1825 -500);
WIRE 16 -1 (-1525 -500)(-1225 -500);
WIRE 16 -1 (-1525 -550)(-1525 -500);
WIRE 16 -1 (-1225 -500)(-950 -500);
WIRE 16 -1 (-1225 -550)(-1225 -500);
WIRE 16 -1 (-675 -500)(-950 -500);
WIRE 16 -1 (-950 -550)(-950 -500);
WIRE 16 -1 (-375 -500)(-675 -500);
WIRE 16 -1 (-675 -550)(-675 -500);
WIRE 16 -1 (-75 -500)(-375 -500);
WIRE 16 -1 (-375 -550)(-375 -500);
WIRE 16 -1 (200 -500)(-75 -500);
WIRE 16 -1 (-75 -550)(-75 -500);
WIRE 16 -1 (525 -500)(200 -500);
WIRE 16 -1 (200 -550)(200 -500);
WIRE 16 -1 (825 -500)(525 -500);
WIRE 16 -1 (525 -550)(525 -500);
WIRE 16 -1 (1125 -500)(825 -500);
WIRE 16 -1 (825 -550)(825 -500);
WIRE 16 -1 (1400 -500)(1125 -500);
WIRE 16 -1 (1125 -550)(1125 -500);
WIRE 16 -1 (1675 -500)(1400 -500);
WIRE 16 -1 (1400 -550)(1400 -500);
WIRE 16 -1 (1975 -500)(1675 -500);
WIRE 16 -1 (1675 -550)(1675 -500);
WIRE 16 -1 (2275 -500)(1975 -500);
WIRE 16 -1 (1975 -550)(1975 -500);
WIRE 16 -1 (2550 -500)(2275 -500);
WIRE 16 -1 (2275 -550)(2275 -500);
WIRE 16 -1 (2550 -550)(2550 -500);
WIRE 16 -1 (-1825 -900)(-1825 -1000);
WIRE 16 -1 (-1525 -900)(-1825 -900);
WIRE 16 -1 (-1825 -750)(-1825 -900);
WIRE 16 -1 (-1225 -900)(-1525 -900);
WIRE 16 -1 (-1525 -750)(-1525 -900);
WIRE 16 -1 (-1225 -900)(-950 -900);
WIRE 16 -1 (-1225 -750)(-1225 -900);
WIRE 16 -1 (-675 -900)(-950 -900);
WIRE 16 -1 (-950 -750)(-950 -900);
WIRE 16 -1 (-375 -900)(-675 -900);
WIRE 16 -1 (-675 -750)(-675 -900);
WIRE 16 -1 (-75 -900)(-375 -900);
WIRE 16 -1 (-375 -750)(-375 -900);
WIRE 16 -1 (200 -900)(-75 -900);
WIRE 16 -1 (-75 -750)(-75 -900);
WIRE 16 -1 (525 -900)(200 -900);
WIRE 16 -1 (200 -750)(200 -900);
WIRE 16 -1 (825 -900)(525 -900);
WIRE 16 -1 (525 -750)(525 -900);
WIRE 16 -1 (1125 -900)(825 -900);
WIRE 16 -1 (825 -750)(825 -900);
WIRE 16 -1 (1400 -900)(1125 -900);
WIRE 16 -1 (1125 -750)(1125 -900);
WIRE 16 -1 (1675 -900)(1400 -900);
WIRE 16 -1 (1400 -750)(1400 -900);
WIRE 16 -1 (1975 -900)(1675 -900);
WIRE 16 -1 (1675 -750)(1675 -900);
WIRE 16 -1 (2275 -900)(1975 -900);
WIRE 16 -1 (1975 -750)(1975 -900);
WIRE 16 -1 (2550 -900)(2275 -900);
WIRE 16 -1 (2275 -750)(2275 -900);
WIRE 16 -1 (2550 -750)(2550 -900);
WIRE 16 -1 (1025 3075)(1025 3025);
WIRE 16 -1 (1025 3025)(1375 3025);
WIRE 16 -1 (700 3025)(1025 3025);
WIRE 16 -1 (1025 2950)(1025 3025);
WIRE 16 -1 (700 2950)(700 3025);
WIRE 16 -1 (1375 2950)(1375 3025);
WIRE 16 -1 (1025 2625)(1025 2575);
WIRE 16 -1 (1375 2625)(1025 2625);
WIRE 16 -1 (700 2625)(1025 2625);
WIRE 16 -1 (1025 2750)(1025 2625);
WIRE 16 -1 (700 2750)(700 2625);
WIRE 16 -1 (1375 2750)(1375 2625);
WIRE 16 -1 (1000 2150)(1000 2100);
WIRE 16 -1 (1000 2100)(1300 2100);
WIRE 16 -1 (1000 2100)(1000 2050);
WIRE 16 -1 (1300 2100)(1600 2100);
WIRE 16 -1 (1300 2100)(1300 2050);
WIRE 16 -1 (1600 2100)(1900 2100);
WIRE 16 -1 (1600 2100)(1600 2050);
WIRE 16 -1 (1900 2100)(1900 2050);
WIRE 16 -1 (1900 1700)(1900 1650);
WIRE 16 -1 (1600 1700)(1900 1700);
WIRE 16 -1 (1900 1700)(1900 1850);
WIRE 16 -1 (1300 1700)(1600 1700);
WIRE 16 -1 (1600 1850)(1600 1700);
WIRE 16 -1 (1000 1700)(1300 1700);
WIRE 16 -1 (1300 1850)(1300 1700);
WIRE 16 -1 (1000 1850)(1000 1700);
WIRE 16 -1 (2000 2775)(2000 2650);
WIRE 16 -1 (2000 2975)(2000 3100);
WIRE 16 -1 (400 1325)(400 1500);
WIRE 16 -1 (400 1500)(275 1500);
WIRE 16 -1 (425 2100)(425 1950);
WIRE 16 -1 (425 1950)(300 1950);
WIRE 16 -1 (3350 -150)(3350 -200);
WIRE 16 -1 (3650 -200)(3350 -200);
WIRE 16 -1 (3350 -300)(3350 -200);
WIRE 16 -1 (3950 -200)(3650 -200);
WIRE 16 -1 (3650 -300)(3650 -200);
WIRE 16 -1 (4250 -200)(3950 -200);
WIRE 16 -1 (3950 -300)(3950 -200);
WIRE 16 -1 (4550 -200)(4250 -200);
WIRE 16 -1 (4250 -300)(4250 -200);
WIRE 16 -1 (4550 -300)(4550 -200);
WIRE 16 -1 (3350 -700)(3350 -725);
WIRE 16 -1 (3650 -700)(3350 -700);
WIRE 16 -1 (3350 -700)(3350 -500);
WIRE 16 -1 (3950 -700)(3650 -700);
WIRE 16 -1 (3650 -500)(3650 -700);
WIRE 16 -1 (4250 -700)(3950 -700);
WIRE 16 -1 (3950 -500)(3950 -700);
WIRE 16 -1 (4550 -700)(4250 -700);
WIRE 16 -1 (4250 -500)(4250 -700);
WIRE 16 -1 (4550 -500)(4550 -700);
WIRE 16 -1 (2875 3025)(2875 3075);
WIRE 16 -1 (2875 3025)(3225 3025);
WIRE 16 -1 (2875 3025)(2875 2950);
WIRE 16 -1 (3625 3025)(3225 3025);
WIRE 16 -1 (3225 2950)(3225 3025);
WIRE 16 -1 (3975 3025)(3625 3025);
WIRE 16 -1 (3625 2950)(3625 3025);
WIRE 16 -1 (4325 3025)(3975 3025);
WIRE 16 -1 (3975 2950)(3975 3025);
WIRE 16 -1 (4725 3025)(4325 3025);
WIRE 16 -1 (4325 2950)(4325 3025);
WIRE 16 -1 (5075 3025)(4725 3025);
WIRE 16 -1 (4725 2950)(4725 3025);
WIRE 16 -1 (5475 3025)(5075 3025);
WIRE 16 -1 (5075 2950)(5075 3025);
WIRE 16 -1 (5475 2950)(5475 3025);
WIRE 16 -1 (2875 2450)(2875 2500);
WIRE 16 -1 (2875 2500)(3225 2500);
WIRE 16 -1 (2875 2750)(2875 2500);
WIRE 16 -1 (3225 2500)(3625 2500);
WIRE 16 -1 (3225 2750)(3225 2500);
WIRE 16 -1 (3975 2500)(3625 2500);
WIRE 16 -1 (3625 2750)(3625 2500);
WIRE 16 -1 (3975 2500)(4325 2500);
WIRE 16 -1 (3975 2750)(3975 2500);
WIRE 16 -1 (4725 2500)(4325 2500);
WIRE 16 -1 (4325 2750)(4325 2500);
WIRE 16 -1 (4725 2500)(5075 2500);
WIRE 16 -1 (4725 2750)(4725 2500);
WIRE 16 -1 (5075 2500)(5475 2500);
WIRE 16 -1 (5075 2750)(5075 2500);
WIRE 16 -1 (5475 2750)(5475 2500);
WIRE 3 682 (600 2400)(600 3225);
WIRE 3 682 (1750 2400)(600 2400);
WIRE 3 682 (600 3225)(1750 3225);
WIRE 3 682 (1750 3225)(1750 2400);
WIRE 16 682 (-1900 2250)(-1900 3350);
WIRE 16 682 (550 2250)(-1900 2250);
WIRE 16 682 (550 3350)(-1900 3350);
WIRE 16 682 (550 3350)(550 2250);
WIRE 3 682 (-1125 2350)(-1800 2350);
WIRE 3 682 (-1125 3200)(-1125 2350);
WIRE 3 682 (-1800 2350)(-1800 3200);
WIRE 3 682 (-1800 3200)(-1125 3200);
WIRE 3 682 (-1050 3200)(-1050 2350);
WIRE 3 682 (450 3200)(-1050 3200);
WIRE 3 682 (-1050 2350)(450 2350);
WIRE 3 682 (450 2350)(450 3200);
WIRE 3 682 (800 2300)(800 1550);
WIRE 3 682 (2200 2300)(800 2300);
WIRE 3 682 (800 1550)(2200 1550);
WIRE 3 682 (2200 1550)(2200 2300);
WIRE 3 682 (1800 2500)(1800 3250);
WIRE 3 682 (2550 2500)(1800 2500);
WIRE 3 682 (1800 3250)(2550 3250);
WIRE 3 682 (2550 3250)(2550 2500);
WIRE 16 2175 (5875 275)(2700 275);
WIRE 16 2175 (5875 275)(5875 3400);
WIRE 16 2175 (2700 275)(2700 3400);
WIRE 16 2175 (2700 3400)(5875 3400);
WIRE 3 682 (2750 3250)(2750 600);
WIRE 3 682 (5950 3250)(2750 3250);
WIRE 3 682 (2750 600)(5950 600);
WIRE 3 682 (5950 600)(5950 3250);
WIRE 16 2175 (2775 2250)(5850 2250);
WIRE 3 682 (3850 1300)(3850 1250);
WIRE 3 682 (3850 1250)(4750 1250);
WIRE 3 682 (4750 1250)(4750 550);
WIRE 3 682 (-1975 -1100)(-1975 400);
WIRE 3 682 (3000 -1100)(-1975 -1100);
WIRE 3 682 (3000 400)(-1975 400);
WIRE 3 682 (3000 400)(3000 -1100);
WIRE 16 682 (5850 -1000)(3100 -1000);
WIRE 16 682 (5850 25)(5850 -1000);
WIRE 16 682 (3100 -1000)(3100 25);
WIRE 16 682 (3100 25)(5850 25);
WIRE 16 -1 (-750 1925)(-1475 1925);
FORCEPROP 2 LAST SIG_NAME VSENSE_PVDDQ_ABC_P
J 0
(-1480 1940);
DISPLAY 0.617021 (-1480 1940);
PAINT ORANGE (-1480 1940);
WIRE 16 -1 (-750 1800)(-750 1925);
WIRE 16 -1 (-350 1800)(-750 1800);
WIRE 16 -1 (-350 1950)(-350 1800);
WIRE 16 -1 (-250 1950)(-350 1950);
WIRE 16 -1 (-250 1800)(-250 1950);
WIRE 16 -1 (0 1950)(-250 1950);
WIRE 16 -1 (-25 1500)(-250 1500);
WIRE 16 -1 (-250 1600)(-250 1500);
WIRE 16 -1 (-250 1500)(-350 1500);
WIRE 16 -1 (-350 1725)(-350 1500);
WIRE 16 -1 (-750 1725)(-350 1725);
WIRE 16 -1 (-750 1675)(-750 1725);
WIRE 16 -1 (-1475 1675)(-750 1675);
FORCEPROP 2 LAST SIG_NAME VSENSE_PVDDQ_ABC_N
J 0
(-1485 1685);
DISPLAY 0.617021 (-1485 1685);
PAINT ORANGE (-1485 1685);
DOT 1 (-200 2600);
DOT 1 (2900 1900);
DOT 1 (4725 3025);
DOT 1 (-1750 3025);
DOT 1 (4625 1475);
DOT 1 (4325 2500);
DOT 1 (3250 1900);
DOT 1 (-950 -200);
DOT 1 (3625 2500);
DOT 1 (5075 2500);
DOT 1 (3625 3025);
DOT 1 (3275 750);
DOT 1 (3950 -700);
DOT 1 (3650 -700);
DOT 1 (4250 -700);
DOT 1 (4250 -200);
DOT 1 (3950 -200);
DOT 1 (3650 -200);
DOT 1 (3975 2500);
DOT 1 (3350 -200);
DOT 1 (3350 -700);
DOT 1 (2875 2500);
DOT 1 (3225 2500);
DOT 1 (1025 2625);
DOT 1 (4725 2500);
DOT 1 (5075 3025);
DOT 1 (3975 3025);
DOT 1 (2875 3025);
DOT 1 (1975 -500);
DOT 1 (2275 -900);
DOT 1 (2275 -500);
DOT 1 (-675 -200);
DOT 1 (-1525 -500);
DOT 1 (-950 200);
DOT 1 (1675 -900);
DOT 1 (525 -500);
DOT 1 (1400 -200);
DOT 1 (1675 -200);
DOT 1 (-375 -200);
DOT 1 (-675 -500);
DOT 1 (-1225 -500);
DOT 1 (-375 -900);
DOT 1 (525 -900);
DOT 1 (1125 -900);
DOT 1 (525 200);
DOT 1 (-1825 -900);
DOT 1 (200 900);
DOT 1 (1125 -200);
DOT 1 (1975 -200);
DOT 1 (4350 1900);
DOT 1 (3650 1900);
DOT 1 (3275 1175);
DOT 1 (3575 750);
DOT 1 (2925 1175);
DOT 1 (2275 200);
DOT 1 (1675 200);
DOT 1 (1400 200);
DOT 1 (1125 200);
DOT 1 (825 200);
DOT 1 (200 200);
DOT 1 (-550 3025);
DOT 1 (-900 3025);
DOT 1 (-250 1500);
DOT 1 (-1825 200);
DOT 1 (1300 1700);
DOT 1 (1300 2100);
DOT 1 (1900 1700);
DOT 1 (1600 1700);
DOT 1 (-1400 2600);
DOT 1 (150 2600);
DOT 1 (-200 3025);
DOT 1 (1000 2100);
DOT 1 (1025 3025);
DOT 1 (-550 2600);
DOT 1 (-250 1950);
DOT 1 (1975 -900);
DOT 1 (1400 -500);
DOT 1 (1125 -500);
DOT 1 (825 -500);
DOT 1 (825 -900);
DOT 1 (200 -500);
DOT 1 (200 -900);
DOT 1 (-75 -500);
DOT 1 (-675 -900);
DOT 1 (-950 -900);
DOT 1 (-1525 -900);
DOT 1 (-75 -900);
DOT 1 (1400 -900);
DOT 1 (-375 -500);
DOT 1 (-1825 -200);
DOT 1 (-75 -200);
DOT 1 (1675 -500);
DOT 1 (1975 200);
DOT 1 (-950 -500);
DOT 1 (825 -200);
DOT 1 (525 -200);
DOT 1 (2275 -200);
DOT 1 (3250 1475);
DOT 1 (4350 1475);
DOT 1 (-375 200);
DOT 1 (-75 200);
DOT 1 (-1525 200);
DOT 1 (-1225 200);
DOT 1 (-1825 -500);
DOT 1 (1600 2100);
DOT 1 (3650 1475);
DOT 1 (-1225 -200);
DOT 1 (-1225 -900);
DOT 1 (3225 3025);
DOT 1 (4325 3025);
DOT 1 (200 -200);
DOT 1 (-1525 -200);
DOT 1 (-675 200);
DOT 1 (4000 1900);
DOT 1 (4000 1475);
FORCENOTE
TOP SIDE: 603
(-775 3050) 0;
DISPLAY LEFT (-775 3050);
DISPLAY 0.638298 (-775 3050);
PAINT PURPLE (-775 3050);
FORCENOTE
TP FAB3-DVT NOPOP FROM SS BOM 20161220
(600 2300) 0;
DISPLAY LEFT (600 2300);
DISPLAY 0.638298 (600 2300);
PAINT RED (600 2300);
FORCENOTE
TP FAB1 CHANGE CONNECTION 0318
(1800 2450) 0;
DISPLAY LEFT (1800 2450);
DISPLAY 0.638298 (1800 2450);
PAINT RED (1800 2450);
FORCENOTE
TP FAB1 CHANGE CAPACITY 0322
(1800 2400) 0;
DISPLAY LEFT (1800 2400);
DISPLAY 0.638298 (1800 2400);
PAINT RED (1800 2400);
FORCENOTE
TP FAB3-DVT NOPOP FROM SS BOM 20161220
(1800 2350) 0;
DISPLAY LEFT (1800 2350);
DISPLAY 0.638298 (1800 2350);
PAINT RED (1800 2350);
FORCENOTE
CAPS TO BE PLACED BETWEEN DIMMS
(2770 3280) 0;
DISPLAY LEFT (2770 3280);
DISPLAY 1.021277 (2770 3280);
PAINT PURPLE (2770 3280);
FORCENOTE
BOTTOM SIDE: 805
(-1700 3050) 0;
DISPLAY LEFT (-1700 3050);
DISPLAY 0.638298 (-1700 3050);
PAINT PURPLE (-1700 3050);
FORCENOTE
TP FAB1 CHAGNE CAP 0311
(600 2350) 0;
DISPLAY LEFT (600 2350);
DISPLAY 0.638298 (600 2350);
PAINT RED (600 2350);
FORCENOTE
TP FAB1 CHANGE CAP 0322
(-925 2200) 0;
DISPLAY LEFT (-925 2200);
DISPLAY 1.021277 (-925 2200);
PAINT RED (-925 2200);
FORCENOTE
TP FAB3-DVT CHANGE CAP IN SS BOM 20161220
(-1850 2150) 0;
DISPLAY LEFT (-1850 2150);
DISPLAY 0.638298 (-1850 2150);
PAINT RED (-1850 2150);
FORCENOTE
TP FAB1 CHANGE CAP 0311
(-1850 2200) 0;
DISPLAY LEFT (-1850 2200);
DISPLAY 0.638298 (-1850 2200);
PAINT RED (-1850 2200);
FORCENOTE
PVDDQ CPU CAVITY CAPS
(-900 2275) 0;
DISPLAY LEFT (-900 2275);
DISPLAY 1.021277 (-900 2275);
PAINT PURPLE (-900 2275);
FORCENOTE
TP FAB1 CHANGE CAP 0314
(800 1475) 0;
DISPLAY LEFT (800 1475);
DISPLAY 1.021277 (800 1475);
PAINT RED (800 1475);
FORCENOTE
TP FAB3-DVT NOPOP FROM SS BOM 20161220
(2750 550) 0;
DISPLAY LEFT (2750 550);
DISPLAY 0.638298 (2750 550);
PAINT RED (2750 550);
FORCENOTE
TP FAB3-DVT CHANGE CAP IN SS BOM 20161220
(4325 500) 0;
DISPLAY LEFT (4325 500);
DISPLAY 0.638298 (4325 500);
PAINT RED (4325 500);
FORCENOTE
CAD NOTE:
(3550 -900) 0;
DISPLAY LEFT (3550 -900);
DISPLAY 1.021277 (3550 -900);
PAINT PURPLE (3550 -900);
FORCENOTE
PLACE NEAR VR OUTPUT INDUCTORS
(3575 -975) 0;
DISPLAY LEFT (3575 -975);
DISPLAY 1.021277 (3575 -975);
PAINT PURPLE (3575 -975);
FORCENOTE
ROOM=VDDQ_ABC_CPU0
(-1825 2275) 0;
DISPLAY LEFT (-1825 2275);
DISPLAY 1.021277 (-1825 2275);
PAINT PURPLE (-1825 2275);
FORCENOTE
TP FAB1 CHANGE CAP 0322
(-1975 -1175) 0;
DISPLAY LEFT (-1975 -1175);
DISPLAY 1.021277 (-1975 -1175);
PAINT RED (-1975 -1175);
FORCENOTE
TP FAB1 CHANGE CAP OF SINGLE SIDE 0504
(-1025 -1175) 0;
DISPLAY LEFT (-1025 -1175);
DISPLAY 1.021277 (-1025 -1175);
PAINT RED (-1025 -1175);
FORCENOTE
ROOM = VDDQ_ABC_PWR_VR
(-1890 -1310) 0;
DISPLAY LEFT (-1890 -1310);
DISPLAY 2.446809 (-1890 -1310);
PAINT PURPLE (-1890 -1310);
FORCENOTE
PVDDQ_ABC VOLTAGE SENSE
(-1445 1405) 0;
DISPLAY LEFT (-1445 1405);
PAINT PURPLE (-1445 1405);
FORCENOTE
5MIL SPACING
(-720 1605) 0;
DISPLAY LEFT (-720 1605);
DISPLAY 0.808511 (-720 1605);
PAINT PURPLE (-720 1605);
FORCENOTE
10MIL WIDTH
(-695 1655) 0;
DISPLAY LEFT (-695 1655);
DISPLAY 0.808511 (-695 1655);
PAINT PURPLE (-695 1655);
FORCENOTE
ROUT AS DIFF PAIR
(-770 1755) 0;
DISPLAY LEFT (-770 1755);
DISPLAY 0.808511 (-770 1755);
PAINT PURPLE (-770 1755);
FORCENOTE
INPUT FILTER
(-355 580) 0;
DISPLAY LEFT (-355 580);
PAINT PURPLE (-355 580);
FORCENOTE
TP FAB1 CHANGE L7F2 PN 0122
(475 850) 0;
DISPLAY LEFT (475 850);
DISPLAY 1.021277 (475 850);
PAINT RED (475 850);
QUIT
